(kicad_sch
	(version 20250114)
	(generator "eeschema")
	(generator_version "9.0")
	(paper "A3")
	(title_block
		(title "RDIMM DDR5 Tester")
		(date "2026-05-21")
		(rev "2.2.0")
		(company "Antmicro")
		(comment 1 "www.antmicro.com")
		(comment 2 "Antmicro")
	)
	(text "NOTE: UART RX/TX cross"
		(exclude_from_sim no)
		(at 234.315 238.125 0)
		(effects
			(font
				(size 1.27 1.27)
			)
			(justify left bottom)
		)
	)
	(text "I2C_SCL"
		(exclude_from_sim no)
		(at 156.21 147.32 0)
		(effects
			(font
				(size 1.27 1.27)
			)
			(justify left bottom)
		)
	)
	(text "Debug FTDI"
		(exclude_from_sim no)
		(at 15.24 20.32 0)
		(effects
			(font
				(size 3 3)
				(thickness 0.6)
				(bold yes)
			)
			(justify left bottom)
		)
	)
	(text "FTDI"
		(exclude_from_sim no)
		(at 16.51 104.14 0)
		(effects
			(font
				(size 2 2)
				(thickness 0.6)
				(bold yes)
			)
			(justify left bottom)
		)
	)
	(text "50 ohm"
		(exclude_from_sim no)
		(at 323.85 62.865 0)
		(effects
			(font
				(size 1.27 1.27)
			)
			(justify left bottom)
		)
	)
	(text "Pass"
		(exclude_from_sim no)
		(at 374.015 62.865 0)
		(effects
			(font
				(size 1.27 1.27)
			)
			(justify left bottom)
		)
	)
	(text "Open"
		(exclude_from_sim no)
		(at 324.485 29.845 0)
		(effects
			(font
				(size 1.27 1.27)
			)
			(justify left bottom)
		)
	)
	(text "Short"
		(exclude_from_sim no)
		(at 372.11 30.48 0)
		(effects
			(font
				(size 1.27 1.27)
			)
			(justify left bottom)
		)
	)
	(text "I2C_SDA_IN"
		(exclude_from_sim no)
		(at 156.21 152.4 0)
		(effects
			(font
				(size 1.27 1.27)
			)
			(justify left bottom)
		)
	)
	(text "Shift register"
		(exclude_from_sim no)
		(at 102.235 236.855 0)
		(effects
			(font
				(size 2 2)
				(thickness 0.4)
				(bold yes)
			)
			(justify left bottom)
		)
	)
	(text "VNA calibration"
		(exclude_from_sim no)
		(at 302.26 19.05 0)
		(effects
			(font
				(size 2 2)
				(thickness 0.4)
				(bold yes)
			)
			(justify left bottom)
		)
	)
	(text "LDO"
		(exclude_from_sim no)
		(at 186.69 19.05 0)
		(effects
			(font
				(size 2 2)
				(thickness 0.4)
				(bold yes)
			)
			(justify left bottom)
		)
	)
	(text "USB-C"
		(exclude_from_sim no)
		(at 15.24 25.4 0)
		(effects
			(font
				(size 2 2)
				(thickness 0.6)
				(bold yes)
			)
			(justify left bottom)
		)
	)
	(text "Logic level translators"
		(exclude_from_sim no)
		(at 224.79 105.41 0)
		(effects
			(font
				(size 2 2)
				(thickness 0.4)
				(bold yes)
			)
			(justify left bottom)
		)
	)
	(text "SPI_EN"
		(exclude_from_sim no)
		(at 147.955 157.48 0)
		(effects
			(font
				(size 1.27 1.27)
			)
			(justify left bottom)
		)
	)
	(text "I2C_SDA_OUT"
		(exclude_from_sim no)
		(at 156.21 149.86 0)
		(effects
			(font
				(size 1.27 1.27)
			)
			(justify left bottom)
		)
	)
	(junction
		(at 104.14 140.97)
		(diameter 0)
		(color 0 0 0 0)
	)
	(junction
		(at 53.34 184.15)
		(diameter 0)
		(color 0 0 0 0)
	)
	(junction
		(at 78.74 88.9)
		(diameter 0)
		(color 0 0 0 0)
	)
	(junction
		(at 111.76 271.78)
		(diameter 0)
		(color 0 0 0 0)
	)
	(junction
		(at 50.8 167.64)
		(diameter 0)
		(color 0 0 0 0)
	)
	(junction
		(at 111.76 259.08)
		(diameter 0)
		(color 0 0 0 0)
	)
	(junction
		(at 205.74 57.15)
		(diameter 0)
		(color 0 0 0 0)
	)
	(junction
		(at 104.14 125.73)
		(diameter 0)
		(color 0 0 0 0)
	)
	(junction
		(at 269.24 41.91)
		(diameter 0)
		(color 0 0 0 0)
	)
	(junction
		(at 200.66 243.84)
		(diameter 0)
		(color 0 0 0 0)
	)
	(junction
		(at 77.47 46.99)
		(diameter 0)
		(color 0 0 0 0)
	)
	(junction
		(at 299.72 176.53)
		(diameter 0)
		(color 0 0 0 0)
	)
	(junction
		(at 233.68 57.15)
		(diameter 0)
		(color 0 0 0 0)
	)
	(junction
		(at 96.52 189.23)
		(diameter 0)
		(color 0 0 0 0)
	)
	(junction
		(at 60.96 148.59)
		(diameter 0)
		(color 0 0 0 0)
	)
	(junction
		(at 256.54 180.34)
		(diameter 0)
		(color 0 0 0 0)
	)
	(junction
		(at 49.53 127)
		(diameter 0)
		(color 0 0 0 0)
	)
	(junction
		(at 91.44 39.37)
		(diameter 0)
		(color 0 0 0 0)
	)
	(junction
		(at 52.07 148.59)
		(diameter 0)
		(color 0 0 0 0)
	)
	(junction
		(at 64.77 127)
		(diameter 0)
		(color 0 0 0 0)
	)
	(junction
		(at 102.87 217.17)
		(diameter 0)
		(color 0 0 0 0)
	)
	(junction
		(at 66.04 54.61)
		(diameter 0)
		(color 0 0 0 0)
	)
	(junction
		(at 57.15 127)
		(diameter 0)
		(color 0 0 0 0)
	)
	(junction
		(at 255.27 203.2)
		(diameter 0)
		(color 0 0 0 0)
	)
	(junction
		(at 59.69 167.64)
		(diameter 0)
		(color 0 0 0 0)
	)
	(junction
		(at 67.31 80.01)
		(diameter 0)
		(color 0 0 0 0)
	)
	(junction
		(at 255.27 224.79)
		(diameter 0)
		(color 0 0 0 0)
	)
	(junction
		(at 63.5 52.07)
		(diameter 0)
		(color 0 0 0 0)
	)
	(junction
		(at 320.04 161.29)
		(diameter 0)
		(color 0 0 0 0)
	)
	(junction
		(at 111.76 265.43)
		(diameter 0)
		(color 0 0 0 0)
	)
	(junction
		(at 41.91 127)
		(diameter 0)
		(color 0 0 0 0)
	)
	(junction
		(at 320.04 170.18)
		(diameter 0)
		(color 0 0 0 0)
	)
	(junction
		(at 177.8 248.92)
		(diameter 0)
		(color 0 0 0 0)
	)
	(junction
		(at 78.74 80.01)
		(diameter 0)
		(color 0 0 0 0)
	)
	(junction
		(at 280.67 133.35)
		(diameter 0)
		(color 0 0 0 0)
	)
	(junction
		(at 76.2 189.23)
		(diameter 0)
		(color 0 0 0 0)
	)
	(junction
		(at 280.67 167.64)
		(diameter 0)
		(color 0 0 0 0)
	)
	(junction
		(at 45.72 184.15)
		(diameter 0)
		(color 0 0 0 0)
	)
	(junction
		(at 322.58 176.53)
		(diameter 0)
		(color 0 0 0 0)
	)
	(junction
		(at 191.77 243.84)
		(diameter 0)
		(color 0 0 0 0)
	)
	(junction
		(at 269.24 59.69)
		(diameter 0)
		(color 0 0 0 0)
	)
	(junction
		(at 102.87 214.63)
		(diameter 0)
		(color 0 0 0 0)
	)
	(junction
		(at 294.64 133.35)
		(diameter 0)
		(color 0 0 0 0)
	)
	(no_connect
		(at 146.05 179.07)
	)
	(no_connect
		(at 146.05 157.48)
	)
	(no_connect
		(at 146.05 215.9)
	)
	(no_connect
		(at 146.05 162.56)
	)
	(no_connect
		(at 146.05 195.58)
	)
	(no_connect
		(at 146.05 135.89)
	)
	(no_connect
		(at 156.21 254)
	)
	(no_connect
		(at 275.59 172.72)
	)
	(no_connect
		(at 146.05 173.99)
	)
	(no_connect
		(at 317.5 41.91)
	)
	(no_connect
		(at 146.05 184.15)
	)
	(no_connect
		(at 146.05 205.74)
	)
	(no_connect
		(at 156.21 251.46)
	)
	(no_connect
		(at 156.21 256.54)
	)
	(no_connect
		(at 146.05 198.12)
	)
	(no_connect
		(at 62.23 64.77)
	)
	(no_connect
		(at 146.05 140.97)
	)
	(no_connect
		(at 146.05 181.61)
	)
	(no_connect
		(at 146.05 208.28)
	)
	(no_connect
		(at 146.05 176.53)
	)
	(no_connect
		(at 146.05 186.69)
	)
	(no_connect
		(at 156.21 248.92)
	)
	(no_connect
		(at 146.05 200.66)
	)
	(no_connect
		(at 146.05 143.51)
	)
	(no_connect
		(at 146.05 203.2)
	)
	(no_connect
		(at 62.23 67.31)
	)
	(no_connect
		(at 156.21 269.24)
	)
	(no_connect
		(at 146.05 165.1)
	)
	(bus_entry
		(at 339.09 229.87)
		(size 2.54 -2.54)
		(stroke
			(width 0)
			(type default)
		)
	)
	(bus_entry
		(at 194.31 147.32)
		(size 2.54 -2.54)
		(stroke
			(width 0)
			(type default)
		)
	)
	(bus_entry
		(at 339.09 208.28)
		(size 2.54 -2.54)
		(stroke
			(width 0)
			(type default)
		)
	)
	(bus_entry
		(at 339.09 176.53)
		(size 2.54 -2.54)
		(stroke
			(width 0)
			(type default)
		)
	)
	(bus_entry
		(at 194.31 149.86)
		(size 2.54 -2.54)
		(stroke
			(width 0)
			(type default)
		)
	)
	(bus_entry
		(at 339.09 170.18)
		(size 2.54 -2.54)
		(stroke
			(width 0)
			(type default)
		)
	)
	(bus_entry
		(at 339.09 205.74)
		(size 2.54 -2.54)
		(stroke
			(width 0)
			(type default)
		)
	)
	(bus_entry
		(at 339.09 143.51)
		(size 2.54 -2.54)
		(stroke
			(width 0)
			(type default)
		)
	)
	(bus_entry
		(at 194.31 152.4)
		(size 2.54 -2.54)
		(stroke
			(width 0)
			(type default)
		)
	)
	(bus_entry
		(at 194.31 160.02)
		(size 2.54 -2.54)
		(stroke
			(width 0)
			(type default)
		)
	)
	(bus_entry
		(at 194.31 154.94)
		(size 2.54 -2.54)
		(stroke
			(width 0)
			(type default)
		)
	)
	(bus_entry
		(at 339.09 146.05)
		(size 2.54 -2.54)
		(stroke
			(width 0)
			(type default)
		)
	)
	(bus_entry
		(at 339.09 138.43)
		(size 2.54 -2.54)
		(stroke
			(width 0)
			(type default)
		)
	)
	(bus_entry
		(at 339.09 140.97)
		(size 2.54 -2.54)
		(stroke
			(width 0)
			(type default)
		)
	)
	(bus_entry
		(at 339.09 227.33)
		(size 2.54 -2.54)
		(stroke
			(width 0)
			(type default)
		)
	)
	(wire
		(pts
			(xy 176.53 261.62) (xy 190.5 261.62)
		)
		(stroke
			(width 0)
			(type default)
		)
	)
	(wire
		(pts
			(xy 373.38 135.89) (xy 373.38 133.35)
		)
		(stroke
			(width 0)
			(type default)
		)
	)
	(wire
		(pts
			(xy 372.11 217.17) (xy 363.22 217.17)
		)
		(stroke
			(width 0)
			(type default)
		)
	)
	(bus
		(pts
			(xy 196.85 144.78) (xy 196.85 147.32)
		)
		(stroke
			(width 0)
			(type default)
		)
	)
	(wire
		(pts
			(xy 104.14 125.73) (xy 105.41 125.73)
		)
		(stroke
			(width 0)
			(type default)
		)
	)
	(wire
		(pts
			(xy 289.56 229.87) (xy 339.09 229.87)
		)
		(stroke
			(width 0)
			(type default)
		)
	)
	(bus
		(pts
			(xy 341.63 140.97) (xy 341.63 143.51)
		)
		(stroke
			(width 0)
			(type default)
		)
	)
	(wire
		(pts
			(xy 78.74 88.9) (xy 78.74 80.01)
		)
		(stroke
			(width 0)
			(type default)
		)
	)
	(wire
		(pts
			(xy 269.24 73.66) (xy 269.24 76.2)
		)
		(stroke
			(width 0)
			(type default)
		)
	)
	(wire
		(pts
			(xy 102.87 214.63) (xy 105.41 214.63)
		)
		(stroke
			(width 0)
			(type default)
		)
	)
	(wire
		(pts
			(xy 383.54 166.37) (xy 383.54 167.64)
		)
		(stroke
			(width 0)
			(type default)
		)
	)
	(wire
		(pts
			(xy 67.31 88.9) (xy 67.31 80.01)
		)
		(stroke
			(width 0)
			(type default)
		)
	)
	(wire
		(pts
			(xy 49.53 127) (xy 57.15 127)
		)
		(stroke
			(width 0)
			(type default)
		)
	)
	(wire
		(pts
			(xy 289.56 227.33) (xy 339.09 227.33)
		)
		(stroke
			(width 0)
			(type default)
		)
	)
	(wire
		(pts
			(xy 128.27 259.08) (xy 128.27 252.73)
		)
		(stroke
			(width 0)
			(type default)
		)
	)
	(wire
		(pts
			(xy 275.59 203.2) (xy 278.13 203.2)
		)
		(stroke
			(width 0)
			(type default)
		)
	)
	(wire
		(pts
			(xy 275.59 146.05) (xy 284.48 146.05)
		)
		(stroke
			(width 0)
			(type default)
		)
	)
	(wire
		(pts
			(xy 60.96 147.32) (xy 60.96 148.59)
		)
		(stroke
			(width 0)
			(type default)
		)
	)
	(bus
		(pts
			(xy 341.63 134.62) (xy 342.9 133.35)
		)
		(stroke
			(width 0)
			(type default)
		)
	)
	(wire
		(pts
			(xy 384.81 200.66) (xy 384.81 198.12)
		)
		(stroke
			(width 0)
			(type default)
		)
	)
	(wire
		(pts
			(xy 373.38 140.97) (xy 373.38 142.24)
		)
		(stroke
			(width 0)
			(type default)
		)
	)
	(bus
		(pts
			(xy 342.9 133.35) (xy 345.44 133.35)
		)
		(stroke
			(width 0)
			(type default)
		)
	)
	(wire
		(pts
			(xy 256.54 180.34) (xy 256.54 181.61)
		)
		(stroke
			(width 0)
			(type default)
		)
	)
	(wire
		(pts
			(xy 278.13 165.1) (xy 278.13 160.02)
		)
		(stroke
			(width 0)
			(type default)
		)
	)
	(wire
		(pts
			(xy 289.56 146.05) (xy 339.09 146.05)
		)
		(stroke
			(width 0)
			(type default)
		)
	)
	(wire
		(pts
			(xy 236.22 224.79) (xy 255.27 224.79)
		)
		(stroke
			(width 0)
			(type default)
		)
	)
	(wire
		(pts
			(xy 242.57 146.05) (xy 257.81 146.05)
		)
		(stroke
			(width 0)
			(type default)
		)
	)
	(wire
		(pts
			(xy 111.76 259.08) (xy 116.84 259.08)
		)
		(stroke
			(width 0)
			(type default)
		)
	)
	(wire
		(pts
			(xy 269.24 41.91) (xy 289.56 41.91)
		)
		(stroke
			(width 0)
			(type default)
		)
	)
	(wire
		(pts
			(xy 233.68 57.15) (xy 243.84 57.15)
		)
		(stroke
			(width 0)
			(type default)
		)
	)
	(wire
		(pts
			(xy 372.11 205.74) (xy 372.11 207.01)
		)
		(stroke
			(width 0)
			(type default)
		)
	)
	(wire
		(pts
			(xy 33.02 127) (xy 41.91 127)
		)
		(stroke
			(width 0)
			(type default)
		)
	)
	(wire
		(pts
			(xy 299.72 176.53) (xy 303.53 176.53)
		)
		(stroke
			(width 0)
			(type default)
		)
	)
	(wire
		(pts
			(xy 289.56 208.28) (xy 339.09 208.28)
		)
		(stroke
			(width 0)
			(type default)
		)
	)
	(wire
		(pts
			(xy 146.05 168.91) (xy 168.91 168.91)
		)
		(stroke
			(width 0)
			(type default)
		)
	)
	(wire
		(pts
			(xy 90.17 140.97) (xy 104.14 140.97)
		)
		(stroke
			(width 0)
			(type default)
		)
	)
	(wire
		(pts
			(xy 77.47 46.99) (xy 81.28 46.99)
		)
		(stroke
			(width 0)
			(type default)
		)
	)
	(wire
		(pts
			(xy 76.2 180.34) (xy 76.2 189.23)
		)
		(stroke
			(width 0)
			(type default)
		)
	)
	(wire
		(pts
			(xy 384.81 205.74) (xy 384.81 207.01)
		)
		(stroke
			(width 0)
			(type default)
		)
	)
	(wire
		(pts
			(xy 289.56 140.97) (xy 339.09 140.97)
		)
		(stroke
			(width 0)
			(type default)
		)
	)
	(wire
		(pts
			(xy 207.01 59.69) (xy 205.74 59.69)
		)
		(stroke
			(width 0)
			(type default)
		)
	)
	(wire
		(pts
			(xy 63.5 52.07) (xy 77.47 52.07)
		)
		(stroke
			(width 0)
			(type default)
		)
	)
	(wire
		(pts
			(xy 280.67 129.54) (xy 280.67 133.35)
		)
		(stroke
			(width 0)
			(type default)
		)
	)
	(wire
		(pts
			(xy 76.2 180.34) (xy 105.41 180.34)
		)
		(stroke
			(width 0)
			(type default)
		)
	)
	(wire
		(pts
			(xy 67.31 80.01) (xy 71.12 80.01)
		)
		(stroke
			(width 0)
			(type default)
		)
	)
	(wire
		(pts
			(xy 275.59 232.41) (xy 276.86 232.41)
		)
		(stroke
			(width 0)
			(type default)
		)
	)
	(bus
		(pts
			(xy 196.85 143.51) (xy 198.12 142.24)
		)
		(stroke
			(width 0)
			(type default)
		)
	)
	(wire
		(pts
			(xy 241.3 165.1) (xy 257.81 165.1)
		)
		(stroke
			(width 0)
			(type default)
		)
	)
	(wire
		(pts
			(xy 139.7 261.62) (xy 156.21 261.62)
		)
		(stroke
			(width 0)
			(type default)
		)
	)
	(wire
		(pts
			(xy 142.24 62.23) (xy 143.51 62.23)
		)
		(stroke
			(width 0)
			(type default)
		)
	)
	(wire
		(pts
			(xy 78.74 72.39) (xy 78.74 80.01)
		)
		(stroke
			(width 0)
			(type default)
		)
	)
	(wire
		(pts
			(xy 275.59 205.74) (xy 284.48 205.74)
		)
		(stroke
			(width 0)
			(type default)
		)
	)
	(wire
		(pts
			(xy 200.66 243.84) (xy 209.55 243.84)
		)
		(stroke
			(width 0)
			(type default)
		)
	)
	(wire
		(pts
			(xy 63.5 52.07) (xy 63.5 57.15)
		)
		(stroke
			(width 0)
			(type default)
		)
	)
	(polyline
		(pts
			(xy 100.33 285.75) (xy 100.33 229.87)
		)
		(stroke
			(width 0)
			(type default)
		)
	)
	(wire
		(pts
			(xy 177.8 248.92) (xy 177.8 256.54)
		)
		(stroke
			(width 0)
			(type default)
		)
	)
	(wire
		(pts
			(xy 49.53 148.59) (xy 52.07 148.59)
		)
		(stroke
			(width 0)
			(type default)
		)
	)
	(wire
		(pts
			(xy 62.23 52.07) (xy 63.5 52.07)
		)
		(stroke
			(width 0)
			(type default)
		)
	)
	(bus
		(pts
			(xy 196.85 143.51) (xy 196.85 144.78)
		)
		(stroke
			(width 0)
			(type default)
		)
	)
	(wire
		(pts
			(xy 256.54 149.86) (xy 256.54 148.59)
		)
		(stroke
			(width 0)
			(type default)
		)
	)
	(wire
		(pts
			(xy 57.15 127) (xy 64.77 127)
		)
		(stroke
			(width 0)
			(type default)
		)
	)
	(wire
		(pts
			(xy 275.59 140.97) (xy 284.48 140.97)
		)
		(stroke
			(width 0)
			(type default)
		)
	)
	(wire
		(pts
			(xy 257.81 172.72) (xy 256.54 172.72)
		)
		(stroke
			(width 0)
			(type default)
		)
	)
	(wire
		(pts
			(xy 64.77 127) (xy 64.77 129.54)
		)
		(stroke
			(width 0)
			(type default)
		)
	)
	(wire
		(pts
			(xy 146.05 128.27) (xy 167.64 128.27)
		)
		(stroke
			(width 0)
			(type default)
		)
	)
	(wire
		(pts
			(xy 280.67 133.35) (xy 284.48 133.35)
		)
		(stroke
			(width 0)
			(type default)
		)
	)
	(wire
		(pts
			(xy 242.57 138.43) (xy 257.81 138.43)
		)
		(stroke
			(width 0)
			(type default)
		)
	)
	(wire
		(pts
			(xy 233.68 54.61) (xy 233.68 57.15)
		)
		(stroke
			(width 0)
			(type default)
		)
	)
	(wire
		(pts
			(xy 146.05 152.4) (xy 173.99 152.4)
		)
		(stroke
			(width 0)
			(type default)
		)
	)
	(wire
		(pts
			(xy 96.52 189.23) (xy 96.52 190.5)
		)
		(stroke
			(width 0)
			(type default)
		)
	)
	(wire
		(pts
			(xy 275.59 177.8) (xy 299.72 177.8)
		)
		(stroke
			(width 0)
			(type default)
		)
	)
	(wire
		(pts
			(xy 384.81 142.24) (xy 384.81 143.51)
		)
		(stroke
			(width 0)
			(type default)
		)
	)
	(wire
		(pts
			(xy 242.57 143.51) (xy 257.81 143.51)
		)
		(stroke
			(width 0)
			(type default)
		)
	)
	(wire
		(pts
			(xy 275.59 229.87) (xy 284.48 229.87)
		)
		(stroke
			(width 0)
			(type default)
		)
	)
	(wire
		(pts
			(xy 269.24 57.15) (xy 269.24 59.69)
		)
		(stroke
			(width 0)
			(type default)
		)
	)
	(wire
		(pts
			(xy 241.3 177.8) (xy 257.81 177.8)
		)
		(stroke
			(width 0)
			(type default)
		)
	)
	(wire
		(pts
			(xy 90.17 138.43) (xy 105.41 138.43)
		)
		(stroke
			(width 0)
			(type default)
		)
	)
	(wire
		(pts
			(xy 139.7 264.16) (xy 156.21 264.16)
		)
		(stroke
			(width 0)
			(type default)
		)
	)
	(wire
		(pts
			(xy 127 264.16) (xy 127 265.43)
		)
		(stroke
			(width 0)
			(type default)
		)
	)
	(polyline
		(pts
			(xy 298.45 12.7) (xy 298.45 97.79)
		)
		(stroke
			(width 0)
			(type default)
		)
	)
	(wire
		(pts
			(xy 241.3 170.18) (xy 257.81 170.18)
		)
		(stroke
			(width 0)
			(type default)
		)
	)
	(wire
		(pts
			(xy 139.7 266.7) (xy 156.21 266.7)
		)
		(stroke
			(width 0)
			(type default)
		)
	)
	(wire
		(pts
			(xy 248.92 48.26) (xy 261.62 48.26)
		)
		(stroke
			(width 0)
			(type default)
		)
	)
	(bus
		(pts
			(xy 341.63 224.79) (xy 341.63 227.33)
		)
		(stroke
			(width 0)
			(type default)
		)
	)
	(wire
		(pts
			(xy 185.42 243.84) (xy 191.77 243.84)
		)
		(stroke
			(width 0)
			(type default)
		)
	)
	(wire
		(pts
			(xy 102.87 203.2) (xy 105.41 203.2)
		)
		(stroke
			(width 0)
			(type default)
		)
	)
	(wire
		(pts
			(xy 111.76 271.78) (xy 111.76 275.59)
		)
		(stroke
			(width 0)
			(type default)
		)
	)
	(wire
		(pts
			(xy 255.27 232.41) (xy 255.27 224.79)
		)
		(stroke
			(width 0)
			(type default)
		)
	)
	(wire
		(pts
			(xy 320.04 158.75) (xy 320.04 161.29)
		)
		(stroke
			(width 0)
			(type default)
		)
	)
	(wire
		(pts
			(xy 59.69 170.18) (xy 59.69 167.64)
		)
		(stroke
			(width 0)
			(type default)
		)
	)
	(wire
		(pts
			(xy 236.22 205.74) (xy 257.81 205.74)
		)
		(stroke
			(width 0)
			(type default)
		)
	)
	(bus
		(pts
			(xy 196.85 149.86) (xy 196.85 152.4)
		)
		(stroke
			(width 0)
			(type default)
		)
	)
	(wire
		(pts
			(xy 139.7 259.08) (xy 156.21 259.08)
		)
		(stroke
			(width 0)
			(type default)
		)
	)
	(wire
		(pts
			(xy 205.74 57.15) (xy 207.01 57.15)
		)
		(stroke
			(width 0)
			(type default)
		)
	)
	(wire
		(pts
			(xy 116.84 252.73) (xy 111.76 252.73)
		)
		(stroke
			(width 0)
			(type default)
		)
	)
	(wire
		(pts
			(xy 60.96 148.59) (xy 71.12 148.59)
		)
		(stroke
			(width 0)
			(type default)
		)
	)
	(wire
		(pts
			(xy 60.96 148.59) (xy 60.96 149.86)
		)
		(stroke
			(width 0)
			(type default)
		)
	)
	(wire
		(pts
			(xy 90.17 172.72) (xy 105.41 172.72)
		)
		(stroke
			(width 0)
			(type default)
		)
	)
	(wire
		(pts
			(xy 91.44 189.23) (xy 96.52 189.23)
		)
		(stroke
			(width 0)
			(type default)
		)
	)
	(wire
		(pts
			(xy 76.2 189.23) (xy 76.2 190.5)
		)
		(stroke
			(width 0)
			(type default)
		)
	)
	(wire
		(pts
			(xy 365.76 82.55) (xy 365.76 83.82)
		)
		(stroke
			(width 0)
			(type default)
		)
	)
	(wire
		(pts
			(xy 185.42 248.92) (xy 185.42 243.84)
		)
		(stroke
			(width 0)
			(type default)
		)
	)
	(wire
		(pts
			(xy 111.76 252.73) (xy 111.76 259.08)
		)
		(stroke
			(width 0)
			(type default)
		)
	)
	(wire
		(pts
			(xy 255.27 203.2) (xy 257.81 203.2)
		)
		(stroke
			(width 0)
			(type default)
		)
	)
	(wire
		(pts
			(xy 320.04 161.29) (xy 322.58 161.29)
		)
		(stroke
			(width 0)
			(type default)
		)
	)
	(wire
		(pts
			(xy 45.72 184.15) (xy 45.72 186.69)
		)
		(stroke
			(width 0)
			(type default)
		)
	)
	(wire
		(pts
			(xy 67.31 44.45) (xy 62.23 44.45)
		)
		(stroke
			(width 0)
			(type default)
		)
	)
	(wire
		(pts
			(xy 77.47 44.45) (xy 77.47 46.99)
		)
		(stroke
			(width 0)
			(type default)
		)
	)
	(wire
		(pts
			(xy 72.39 44.45) (xy 77.47 44.45)
		)
		(stroke
			(width 0)
			(type default)
		)
	)
	(wire
		(pts
			(xy 308.61 170.18) (xy 320.04 170.18)
		)
		(stroke
			(width 0)
			(type default)
		)
	)
	(wire
		(pts
			(xy 91.44 39.37) (xy 95.25 39.37)
		)
		(stroke
			(width 0)
			(type default)
		)
	)
	(wire
		(pts
			(xy 200.66 246.38) (xy 200.66 243.84)
		)
		(stroke
			(width 0)
			(type default)
		)
	)
	(wire
		(pts
			(xy 102.87 214.63) (xy 102.87 217.17)
		)
		(stroke
			(width 0)
			(type default)
		)
	)
	(bus
		(pts
			(xy 341.63 135.89) (xy 341.63 138.43)
		)
		(stroke
			(width 0)
			(type default)
		)
	)
	(polyline
		(pts
			(xy 182.88 97.79) (xy 182.88 86.36)
		)
		(stroke
			(width 0)
			(type default)
		)
	)
	(wire
		(pts
			(xy 83.82 189.23) (xy 76.2 189.23)
		)
		(stroke
			(width 0)
			(type default)
		)
	)
	(wire
		(pts
			(xy 179.07 152.4) (xy 194.31 152.4)
		)
		(stroke
			(width 0)
			(type default)
		)
	)
	(wire
		(pts
			(xy 102.87 203.2) (xy 102.87 207.01)
		)
		(stroke
			(width 0)
			(type default)
		)
	)
	(wire
		(pts
			(xy 59.69 167.64) (xy 69.85 167.64)
		)
		(stroke
			(width 0)
			(type default)
		)
	)
	(wire
		(pts
			(xy 67.31 74.93) (xy 62.23 74.93)
		)
		(stroke
			(width 0)
			(type default)
		)
	)
	(wire
		(pts
			(xy 320.04 170.18) (xy 339.09 170.18)
		)
		(stroke
			(width 0)
			(type default)
		)
	)
	(wire
		(pts
			(xy 62.23 39.37) (xy 91.44 39.37)
		)
		(stroke
			(width 0)
			(type default)
		)
	)
	(bus
		(pts
			(xy 341.63 200.66) (xy 342.9 199.39)
		)
		(stroke
			(width 0)
			(type default)
		)
	)
	(wire
		(pts
			(xy 280.67 167.64) (xy 288.29 167.64)
		)
		(stroke
			(width 0)
			(type default)
		)
	)
	(wire
		(pts
			(xy 121.92 265.43) (xy 127 265.43)
		)
		(stroke
			(width 0)
			(type default)
		)
	)
	(wire
		(pts
			(xy 91.44 49.53) (xy 91.44 46.99)
		)
		(stroke
			(width 0)
			(type default)
		)
	)
	(wire
		(pts
			(xy 104.14 132.08) (xy 105.41 132.08)
		)
		(stroke
			(width 0)
			(type default)
		)
	)
	(bus
		(pts
			(xy 341.63 222.25) (xy 342.9 220.98)
		)
		(stroke
			(width 0)
			(type default)
		)
	)
	(wire
		(pts
			(xy 49.53 127) (xy 49.53 129.54)
		)
		(stroke
			(width 0)
			(type default)
		)
	)
	(wire
		(pts
			(xy 176.53 259.08) (xy 190.5 259.08)
		)
		(stroke
			(width 0)
			(type default)
		)
	)
	(wire
		(pts
			(xy 71.12 88.9) (xy 67.31 88.9)
		)
		(stroke
			(width 0)
			(type default)
		)
	)
	(wire
		(pts
			(xy 90.17 125.73) (xy 104.14 125.73)
		)
		(stroke
			(width 0)
			(type default)
		)
	)
	(wire
		(pts
			(xy 318.77 76.2) (xy 326.39 76.2)
		)
		(stroke
			(width 0)
			(type default)
		)
	)
	(wire
		(pts
			(xy 236.22 203.2) (xy 255.27 203.2)
		)
		(stroke
			(width 0)
			(type default)
		)
	)
	(wire
		(pts
			(xy 227.33 57.15) (xy 233.68 57.15)
		)
		(stroke
			(width 0)
			(type default)
		)
	)
	(wire
		(pts
			(xy 242.57 140.97) (xy 257.81 140.97)
		)
		(stroke
			(width 0)
			(type default)
		)
	)
	(wire
		(pts
			(xy 146.05 147.32) (xy 173.99 147.32)
		)
		(stroke
			(width 0)
			(type default)
		)
	)
	(wire
		(pts
			(xy 179.07 149.86) (xy 194.31 149.86)
		)
		(stroke
			(width 0)
			(type default)
		)
	)
	(wire
		(pts
			(xy 372.11 76.2) (xy 384.81 76.2)
		)
		(stroke
			(width 0)
			(type default)
		)
	)
	(wire
		(pts
			(xy 49.53 167.64) (xy 50.8 167.64)
		)
		(stroke
			(width 0)
			(type default)
		)
	)
	(bus
		(pts
			(xy 341.63 222.25) (xy 341.63 224.79)
		)
		(stroke
			(width 0)
			(type default)
		)
	)
	(bus
		(pts
			(xy 342.9 199.39) (xy 345.44 199.39)
		)
		(stroke
			(width 0)
			(type default)
		)
	)
	(wire
		(pts
			(xy 278.13 224.79) (xy 278.13 222.25)
		)
		(stroke
			(width 0)
			(type default)
		)
	)
	(wire
		(pts
			(xy 191.77 251.46) (xy 191.77 254)
		)
		(stroke
			(width 0)
			(type default)
		)
	)
	(wire
		(pts
			(xy 198.12 67.31) (xy 198.12 64.77)
		)
		(stroke
			(width 0)
			(type default)
		)
	)
	(wire
		(pts
			(xy 372.11 198.12) (xy 363.22 198.12)
		)
		(stroke
			(width 0)
			(type default)
		)
	)
	(wire
		(pts
			(xy 332.74 82.55) (xy 332.74 83.82)
		)
		(stroke
			(width 0)
			(type default)
		)
	)
	(wire
		(pts
			(xy 275.59 170.18) (xy 303.53 170.18)
		)
		(stroke
			(width 0)
			(type default)
		)
	)
	(wire
		(pts
			(xy 384.81 137.16) (xy 384.81 134.62)
		)
		(stroke
			(width 0)
			(type default)
		)
	)
	(wire
		(pts
			(xy 255.27 224.79) (xy 257.81 224.79)
		)
		(stroke
			(width 0)
			(type default)
		)
	)
	(wire
		(pts
			(xy 90.17 135.89) (xy 105.41 135.89)
		)
		(stroke
			(width 0)
			(type default)
		)
	)
	(polyline
		(pts
			(xy 407.67 97.79) (xy 182.88 97.79)
		)
		(stroke
			(width 0)
			(type default)
		)
	)
	(wire
		(pts
			(xy 198.12 57.15) (xy 205.74 57.15)
		)
		(stroke
			(width 0)
			(type default)
		)
	)
	(wire
		(pts
			(xy 104.14 162.56) (xy 105.41 162.56)
		)
		(stroke
			(width 0)
			(type default)
		)
	)
	(wire
		(pts
			(xy 59.69 176.53) (xy 59.69 175.26)
		)
		(stroke
			(width 0)
			(type default)
		)
	)
	(wire
		(pts
			(xy 158.75 213.36) (xy 146.05 213.36)
		)
		(stroke
			(width 0)
			(type default)
		)
	)
	(wire
		(pts
			(xy 64.77 125.73) (xy 64.77 127)
		)
		(stroke
			(width 0)
			(type default)
		)
	)
	(bus
		(pts
			(xy 341.63 165.1) (xy 342.9 163.83)
		)
		(stroke
			(width 0)
			(type default)
		)
	)
	(bus
		(pts
			(xy 196.85 147.32) (xy 196.85 149.86)
		)
		(stroke
			(width 0)
			(type default)
		)
	)
	(wire
		(pts
			(xy 77.47 46.99) (xy 72.39 46.99)
		)
		(stroke
			(width 0)
			(type default)
		)
	)
	(wire
		(pts
			(xy 191.77 243.84) (xy 191.77 246.38)
		)
		(stroke
			(width 0)
			(type default)
		)
	)
	(wire
		(pts
			(xy 236.22 227.33) (xy 257.81 227.33)
		)
		(stroke
			(width 0)
			(type default)
		)
	)
	(wire
		(pts
			(xy 176.53 248.92) (xy 177.8 248.92)
		)
		(stroke
			(width 0)
			(type default)
		)
	)
	(wire
		(pts
			(xy 67.31 46.99) (xy 62.23 46.99)
		)
		(stroke
			(width 0)
			(type default)
		)
	)
	(bus
		(pts
			(xy 341.63 167.64) (xy 341.63 173.99)
		)
		(stroke
			(width 0)
			(type default)
		)
	)
	(wire
		(pts
			(xy 78.74 88.9) (xy 78.74 90.17)
		)
		(stroke
			(width 0)
			(type default)
		)
	)
	(wire
		(pts
			(xy 372.11 161.29) (xy 372.11 158.75)
		)
		(stroke
			(width 0)
			(type default)
		)
	)
	(wire
		(pts
			(xy 76.2 88.9) (xy 78.74 88.9)
		)
		(stroke
			(width 0)
			(type default)
		)
	)
	(wire
		(pts
			(xy 176.53 264.16) (xy 190.5 264.16)
		)
		(stroke
			(width 0)
			(type default)
		)
	)
	(wire
		(pts
			(xy 299.72 176.53) (xy 299.72 175.26)
		)
		(stroke
			(width 0)
			(type default)
		)
	)
	(wire
		(pts
			(xy 384.81 224.79) (xy 384.81 226.06)
		)
		(stroke
			(width 0)
			(type default)
		)
	)
	(wire
		(pts
			(xy 90.17 148.59) (xy 105.41 148.59)
		)
		(stroke
			(width 0)
			(type default)
		)
	)
	(wire
		(pts
			(xy 275.59 208.28) (xy 284.48 208.28)
		)
		(stroke
			(width 0)
			(type default)
		)
	)
	(wire
		(pts
			(xy 121.92 259.08) (xy 127 259.08)
		)
		(stroke
			(width 0)
			(type default)
		)
	)
	(wire
		(pts
			(xy 322.58 176.53) (xy 339.09 176.53)
		)
		(stroke
			(width 0)
			(type default)
		)
	)
	(wire
		(pts
			(xy 62.23 59.69) (xy 66.04 59.69)
		)
		(stroke
			(width 0)
			(type default)
		)
	)
	(wire
		(pts
			(xy 90.17 162.56) (xy 99.06 162.56)
		)
		(stroke
			(width 0)
			(type default)
		)
	)
	(wire
		(pts
			(xy 318.77 81.28) (xy 318.77 83.82)
		)
		(stroke
			(width 0)
			(type default)
		)
	)
	(wire
		(pts
			(xy 66.04 59.69) (xy 66.04 54.61)
		)
		(stroke
			(width 0)
			(type default)
		)
	)
	(wire
		(pts
			(xy 146.05 125.73) (xy 167.64 125.73)
		)
		(stroke
			(width 0)
			(type default)
		)
	)
	(wire
		(pts
			(xy 242.57 133.35) (xy 257.81 133.35)
		)
		(stroke
			(width 0)
			(type default)
		)
	)
	(bus
		(pts
			(xy 341.63 165.1) (xy 341.63 167.64)
		)
		(stroke
			(width 0)
			(type default)
		)
	)
	(wire
		(pts
			(xy 153.67 57.15) (xy 142.24 57.15)
		)
		(stroke
			(width 0)
			(type default)
		)
	)
	(bus
		(pts
			(xy 342.9 163.83) (xy 345.44 163.83)
		)
		(stroke
			(width 0)
			(type default)
		)
	)
	(wire
		(pts
			(xy 257.81 210.82) (xy 255.27 210.82)
		)
		(stroke
			(width 0)
			(type default)
		)
	)
	(wire
		(pts
			(xy 176.53 254) (xy 191.77 254)
		)
		(stroke
			(width 0)
			(type default)
		)
	)
	(wire
		(pts
			(xy 373.38 41.91) (xy 370.84 41.91)
		)
		(stroke
			(width 0)
			(type default)
		)
	)
	(wire
		(pts
			(xy 275.59 227.33) (xy 284.48 227.33)
		)
		(stroke
			(width 0)
			(type default)
		)
	)
	(wire
		(pts
			(xy 294.64 133.35) (xy 294.64 135.89)
		)
		(stroke
			(width 0)
			(type default)
		)
	)
	(wire
		(pts
			(xy 146.05 138.43) (xy 166.37 138.43)
		)
		(stroke
			(width 0)
			(type default)
		)
	)
	(bus
		(pts
			(xy 341.63 203.2) (xy 341.63 205.74)
		)
		(stroke
			(width 0)
			(type default)
		)
	)
	(wire
		(pts
			(xy 275.59 143.51) (xy 284.48 143.51)
		)
		(stroke
			(width 0)
			(type default)
		)
	)
	(wire
		(pts
			(xy 96.52 185.42) (xy 105.41 185.42)
		)
		(stroke
			(width 0)
			(type default)
		)
	)
	(wire
		(pts
			(xy 233.68 67.31) (xy 233.68 64.77)
		)
		(stroke
			(width 0)
			(type default)
		)
	)
	(wire
		(pts
			(xy 41.91 127) (xy 49.53 127)
		)
		(stroke
			(width 0)
			(type default)
		)
	)
	(polyline
		(pts
			(xy 219.71 97.79) (xy 219.71 284.48)
		)
		(stroke
			(width 0)
			(type default)
		)
	)
	(wire
		(pts
			(xy 228.6 59.69) (xy 228.6 67.31)
		)
		(stroke
			(width 0)
			(type default)
		)
	)
	(bus
		(pts
			(xy 342.9 220.98) (xy 345.44 220.98)
		)
		(stroke
			(width 0)
			(type default)
		)
	)
	(wire
		(pts
			(xy 60.96 184.15) (xy 60.96 186.69)
		)
		(stroke
			(width 0)
			(type default)
		)
	)
	(wire
		(pts
			(xy 104.14 140.97) (xy 104.14 132.08)
		)
		(stroke
			(width 0)
			(type default)
		)
	)
	(wire
		(pts
			(xy 67.31 74.93) (xy 67.31 80.01)
		)
		(stroke
			(width 0)
			(type default)
		)
	)
	(wire
		(pts
			(xy 293.37 165.1) (xy 311.15 165.1)
		)
		(stroke
			(width 0)
			(type default)
		)
	)
	(wire
		(pts
			(xy 146.05 130.81) (xy 167.64 130.81)
		)
		(stroke
			(width 0)
			(type default)
		)
	)
	(wire
		(pts
			(xy 275.59 165.1) (xy 278.13 165.1)
		)
		(stroke
			(width 0)
			(type default)
		)
	)
	(wire
		(pts
			(xy 33.02 184.15) (xy 45.72 184.15)
		)
		(stroke
			(width 0)
			(type default)
		)
	)
	(wire
		(pts
			(xy 153.67 54.61) (xy 142.24 54.61)
		)
		(stroke
			(width 0)
			(type default)
		)
	)
	(wire
		(pts
			(xy 121.92 252.73) (xy 128.27 252.73)
		)
		(stroke
			(width 0)
			(type default)
		)
	)
	(wire
		(pts
			(xy 33.02 167.64) (xy 44.45 167.64)
		)
		(stroke
			(width 0)
			(type default)
		)
	)
	(wire
		(pts
			(xy 269.24 41.91) (xy 269.24 44.45)
		)
		(stroke
			(width 0)
			(type default)
		)
	)
	(wire
		(pts
			(xy 289.56 143.51) (xy 339.09 143.51)
		)
		(stroke
			(width 0)
			(type default)
		)
	)
	(wire
		(pts
			(xy 146.05 193.04) (xy 168.91 193.04)
		)
		(stroke
			(width 0)
			(type default)
		)
	)
	(polyline
		(pts
			(xy 12.7 97.79) (xy 182.88 97.79)
		)
		(stroke
			(width 0)
			(type default)
		)
	)
	(wire
		(pts
			(xy 278.13 203.2) (xy 278.13 198.12)
		)
		(stroke
			(width 0)
			(type default)
		)
	)
	(wire
		(pts
			(xy 275.59 224.79) (xy 278.13 224.79)
		)
		(stroke
			(width 0)
			(type default)
		)
	)
	(wire
		(pts
			(xy 91.44 41.91) (xy 91.44 39.37)
		)
		(stroke
			(width 0)
			(type default)
		)
	)
	(wire
		(pts
			(xy 60.96 156.21) (xy 60.96 154.94)
		)
		(stroke
			(width 0)
			(type default)
		)
	)
	(wire
		(pts
			(xy 50.8 176.53) (xy 50.8 175.26)
		)
		(stroke
			(width 0)
			(type default)
		)
	)
	(wire
		(pts
			(xy 255.27 210.82) (xy 255.27 203.2)
		)
		(stroke
			(width 0)
			(type default)
		)
	)
	(wire
		(pts
			(xy 372.11 224.79) (xy 372.11 226.06)
		)
		(stroke
			(width 0)
			(type default)
		)
	)
	(wire
		(pts
			(xy 275.59 138.43) (xy 284.48 138.43)
		)
		(stroke
			(width 0)
			(type default)
		)
	)
	(wire
		(pts
			(xy 104.14 140.97) (xy 105.41 140.97)
		)
		(stroke
			(width 0)
			(type default)
		)
	)
	(wire
		(pts
			(xy 289.56 41.91) (xy 289.56 48.26)
		)
		(stroke
			(width 0)
			(type default)
		)
	)
	(wire
		(pts
			(xy 275.59 133.35) (xy 280.67 133.35)
		)
		(stroke
			(width 0)
			(type default)
		)
	)
	(polyline
		(pts
			(xy 100.33 229.87) (xy 219.71 229.87)
		)
		(stroke
			(width 0)
			(type default)
		)
	)
	(wire
		(pts
			(xy 52.07 156.21) (xy 52.07 154.94)
		)
		(stroke
			(width 0)
			(type default)
		)
	)
	(wire
		(pts
			(xy 257.81 232.41) (xy 255.27 232.41)
		)
		(stroke
			(width 0)
			(type default)
		)
	)
	(wire
		(pts
			(xy 127 261.62) (xy 134.62 261.62)
		)
		(stroke
			(width 0)
			(type default)
		)
	)
	(wire
		(pts
			(xy 256.54 148.59) (xy 257.81 148.59)
		)
		(stroke
			(width 0)
			(type default)
		)
	)
	(wire
		(pts
			(xy 90.17 151.13) (xy 105.41 151.13)
		)
		(stroke
			(width 0)
			(type default)
		)
	)
	(wire
		(pts
			(xy 179.07 160.02) (xy 194.31 160.02)
		)
		(stroke
			(width 0)
			(type default)
		)
	)
	(bus
		(pts
			(xy 196.85 152.4) (xy 196.85 157.48)
		)
		(stroke
			(width 0)
			(type default)
		)
	)
	(wire
		(pts
			(xy 227.33 59.69) (xy 228.6 59.69)
		)
		(stroke
			(width 0)
			(type default)
		)
	)
	(wire
		(pts
			(xy 289.56 133.35) (xy 294.64 133.35)
		)
		(stroke
			(width 0)
			(type default)
		)
	)
	(wire
		(pts
			(xy 96.52 185.42) (xy 96.52 189.23)
		)
		(stroke
			(width 0)
			(type default)
		)
	)
	(wire
		(pts
			(xy 236.22 208.28) (xy 257.81 208.28)
		)
		(stroke
			(width 0)
			(type default)
		)
	)
	(wire
		(pts
			(xy 200.66 243.84) (xy 191.77 243.84)
		)
		(stroke
			(width 0)
			(type default)
		)
	)
	(wire
		(pts
			(xy 372.11 166.37) (xy 372.11 167.64)
		)
		(stroke
			(width 0)
			(type default)
		)
	)
	(wire
		(pts
			(xy 391.16 82.55) (xy 391.16 83.82)
		)
		(stroke
			(width 0)
			(type default)
		)
	)
	(wire
		(pts
			(xy 205.74 57.15) (xy 205.74 59.69)
		)
		(stroke
			(width 0)
			(type default)
		)
	)
	(wire
		(pts
			(xy 102.87 212.09) (xy 102.87 214.63)
		)
		(stroke
			(width 0)
			(type default)
		)
	)
	(wire
		(pts
			(xy 50.8 167.64) (xy 59.69 167.64)
		)
		(stroke
			(width 0)
			(type default)
		)
	)
	(wire
		(pts
			(xy 372.11 200.66) (xy 372.11 198.12)
		)
		(stroke
			(width 0)
			(type default)
		)
	)
	(wire
		(pts
			(xy 111.76 259.08) (xy 111.76 265.43)
		)
		(stroke
			(width 0)
			(type default)
		)
	)
	(wire
		(pts
			(xy 289.56 53.34) (xy 289.56 59.69)
		)
		(stroke
			(width 0)
			(type default)
		)
	)
	(wire
		(pts
			(xy 111.76 271.78) (xy 116.84 271.78)
		)
		(stroke
			(width 0)
			(type default)
		)
	)
	(wire
		(pts
			(xy 176.53 269.24) (xy 177.8 269.24)
		)
		(stroke
			(width 0)
			(type default)
		)
	)
	(wire
		(pts
			(xy 90.17 170.18) (xy 105.41 170.18)
		)
		(stroke
			(width 0)
			(type default)
		)
	)
	(wire
		(pts
			(xy 289.56 205.74) (xy 339.09 205.74)
		)
		(stroke
			(width 0)
			(type default)
		)
	)
	(wire
		(pts
			(xy 146.05 149.86) (xy 173.99 149.86)
		)
		(stroke
			(width 0)
			(type default)
		)
	)
	(wire
		(pts
			(xy 373.38 133.35) (xy 364.49 133.35)
		)
		(stroke
			(width 0)
			(type default)
		)
	)
	(wire
		(pts
			(xy 45.72 184.15) (xy 53.34 184.15)
		)
		(stroke
			(width 0)
			(type default)
		)
	)
	(wire
		(pts
			(xy 370.84 41.91) (xy 370.84 49.53)
		)
		(stroke
			(width 0)
			(type default)
		)
	)
	(wire
		(pts
			(xy 289.56 59.69) (xy 269.24 59.69)
		)
		(stroke
			(width 0)
			(type default)
		)
	)
	(wire
		(pts
			(xy 142.24 59.69) (xy 153.67 59.69)
		)
		(stroke
			(width 0)
			(type default)
		)
	)
	(wire
		(pts
			(xy 288.29 165.1) (xy 280.67 165.1)
		)
		(stroke
			(width 0)
			(type default)
		)
	)
	(wire
		(pts
			(xy 241.3 175.26) (xy 257.81 175.26)
		)
		(stroke
			(width 0)
			(type default)
		)
	)
	(wire
		(pts
			(xy 53.34 184.15) (xy 60.96 184.15)
		)
		(stroke
			(width 0)
			(type default)
		)
	)
	(wire
		(pts
			(xy 105.41 128.27) (xy 104.14 128.27)
		)
		(stroke
			(width 0)
			(type default)
		)
	)
	(wire
		(pts
			(xy 41.91 127) (xy 41.91 129.54)
		)
		(stroke
			(width 0)
			(type default)
		)
	)
	(wire
		(pts
			(xy 200.66 251.46) (xy 200.66 252.73)
		)
		(stroke
			(width 0)
			(type default)
		)
	)
	(wire
		(pts
			(xy 198.12 57.15) (xy 198.12 59.69)
		)
		(stroke
			(width 0)
			(type default)
		)
	)
	(wire
		(pts
			(xy 33.02 148.59) (xy 44.45 148.59)
		)
		(stroke
			(width 0)
			(type default)
		)
	)
	(wire
		(pts
			(xy 66.04 54.61) (xy 77.47 54.61)
		)
		(stroke
			(width 0)
			(type default)
		)
	)
	(wire
		(pts
			(xy 57.15 127) (xy 57.15 129.54)
		)
		(stroke
			(width 0)
			(type default)
		)
	)
	(wire
		(pts
			(xy 276.86 232.41) (xy 276.86 233.68)
		)
		(stroke
			(width 0)
			(type default)
		)
	)
	(wire
		(pts
			(xy 269.24 38.1) (xy 269.24 41.91)
		)
		(stroke
			(width 0)
			(type default)
		)
	)
	(wire
		(pts
			(xy 62.23 57.15) (xy 63.5 57.15)
		)
		(stroke
			(width 0)
			(type default)
		)
	)
	(bus
		(pts
			(xy 341.63 138.43) (xy 341.63 140.97)
		)
		(stroke
			(width 0)
			(type default)
		)
	)
	(wire
		(pts
			(xy 269.24 38.1) (xy 283.21 38.1)
		)
		(stroke
			(width 0)
			(type default)
		)
	)
	(wire
		(pts
			(xy 275.59 135.89) (xy 294.64 135.89)
		)
		(stroke
			(width 0)
			(type default)
		)
	)
	(wire
		(pts
			(xy 142.24 52.07) (xy 153.67 52.07)
		)
		(stroke
			(width 0)
			(type default)
		)
	)
	(wire
		(pts
			(xy 121.92 271.78) (xy 128.27 271.78)
		)
		(stroke
			(width 0)
			(type default)
		)
	)
	(wire
		(pts
			(xy 78.74 72.39) (xy 62.23 72.39)
		)
		(stroke
			(width 0)
			(type default)
		)
	)
	(wire
		(pts
			(xy 177.8 248.92) (xy 185.42 248.92)
		)
		(stroke
			(width 0)
			(type default)
		)
	)
	(wire
		(pts
			(xy 52.07 148.59) (xy 60.96 148.59)
		)
		(stroke
			(width 0)
			(type default)
		)
	)
	(bus
		(pts
			(xy 341.63 200.66) (xy 341.63 203.2)
		)
		(stroke
			(width 0)
			(type default)
		)
	)
	(wire
		(pts
			(xy 308.61 176.53) (xy 322.58 176.53)
		)
		(stroke
			(width 0)
			(type default)
		)
	)
	(wire
		(pts
			(xy 256.54 172.72) (xy 256.54 180.34)
		)
		(stroke
			(width 0)
			(type default)
		)
	)
	(wire
		(pts
			(xy 328.93 48.26) (xy 328.93 49.53)
		)
		(stroke
			(width 0)
			(type default)
		)
	)
	(wire
		(pts
			(xy 269.24 62.23) (xy 269.24 59.69)
		)
		(stroke
			(width 0)
			(type default)
		)
	)
	(wire
		(pts
			(xy 294.64 133.35) (xy 297.18 133.35)
		)
		(stroke
			(width 0)
			(type default)
		)
	)
	(wire
		(pts
			(xy 384.81 219.71) (xy 384.81 217.17)
		)
		(stroke
			(width 0)
			(type default)
		)
	)
	(wire
		(pts
			(xy 128.27 259.08) (xy 134.62 259.08)
		)
		(stroke
			(width 0)
			(type default)
		)
	)
	(wire
		(pts
			(xy 104.14 128.27) (xy 104.14 125.73)
		)
		(stroke
			(width 0)
			(type default)
		)
	)
	(wire
		(pts
			(xy 87.63 194.31) (xy 87.63 195.58)
		)
		(stroke
			(width 0)
			(type default)
		)
	)
	(wire
		(pts
			(xy 293.37 167.64) (xy 311.15 167.64)
		)
		(stroke
			(width 0)
			(type default)
		)
	)
	(wire
		(pts
			(xy 128.27 266.7) (xy 128.27 271.78)
		)
		(stroke
			(width 0)
			(type default)
		)
	)
	(wire
		(pts
			(xy 146.05 154.94) (xy 173.99 154.94)
		)
		(stroke
			(width 0)
			(type default)
		)
	)
	(wire
		(pts
			(xy 90.17 175.26) (xy 105.41 175.26)
		)
		(stroke
			(width 0)
			(type default)
		)
	)
	(wire
		(pts
			(xy 128.27 266.7) (xy 134.62 266.7)
		)
		(stroke
			(width 0)
			(type default)
		)
	)
	(wire
		(pts
			(xy 320.04 166.37) (xy 320.04 170.18)
		)
		(stroke
			(width 0)
			(type default)
		)
	)
	(wire
		(pts
			(xy 280.67 167.64) (xy 280.67 165.1)
		)
		(stroke
			(width 0)
			(type default)
		)
	)
	(wire
		(pts
			(xy 127 261.62) (xy 127 259.08)
		)
		(stroke
			(width 0)
			(type default)
		)
	)
	(wire
		(pts
			(xy 383.54 161.29) (xy 383.54 158.75)
		)
		(stroke
			(width 0)
			(type default)
		)
	)
	(bus
		(pts
			(xy 200.66 142.24) (xy 198.12 142.24)
		)
		(stroke
			(width 0)
			(type default)
		)
	)
	(wire
		(pts
			(xy 179.07 147.32) (xy 194.31 147.32)
		)
		(stroke
			(width 0)
			(type default)
		)
	)
	(wire
		(pts
			(xy 275.59 167.64) (xy 280.67 167.64)
		)
		(stroke
			(width 0)
			(type default)
		)
	)
	(wire
		(pts
			(xy 379.73 48.26) (xy 379.73 49.53)
		)
		(stroke
			(width 0)
			(type default)
		)
	)
	(wire
		(pts
			(xy 127 264.16) (xy 134.62 264.16)
		)
		(stroke
			(width 0)
			(type default)
		)
	)
	(wire
		(pts
			(xy 102.87 217.17) (xy 102.87 219.71)
		)
		(stroke
			(width 0)
			(type default)
		)
	)
	(wire
		(pts
			(xy 299.72 177.8) (xy 299.72 176.53)
		)
		(stroke
			(width 0)
			(type default)
		)
	)
	(wire
		(pts
			(xy 372.11 158.75) (xy 363.22 158.75)
		)
		(stroke
			(width 0)
			(type default)
		)
	)
	(wire
		(pts
			(xy 179.07 154.94) (xy 194.31 154.94)
		)
		(stroke
			(width 0)
			(type default)
		)
	)
	(wire
		(pts
			(xy 62.23 54.61) (xy 66.04 54.61)
		)
		(stroke
			(width 0)
			(type default)
		)
	)
	(bus
		(pts
			(xy 341.63 134.62) (xy 341.63 135.89)
		)
		(stroke
			(width 0)
			(type default)
		)
	)
	(wire
		(pts
			(xy 275.59 210.82) (xy 276.86 210.82)
		)
		(stroke
			(width 0)
			(type default)
		)
	)
	(wire
		(pts
			(xy 233.68 57.15) (xy 233.68 59.69)
		)
		(stroke
			(width 0)
			(type default)
		)
	)
	(wire
		(pts
			(xy 294.64 175.26) (xy 299.72 175.26)
		)
		(stroke
			(width 0)
			(type default)
		)
	)
	(wire
		(pts
			(xy 289.56 138.43) (xy 339.09 138.43)
		)
		(stroke
			(width 0)
			(type default)
		)
	)
	(wire
		(pts
			(xy 111.76 265.43) (xy 116.84 265.43)
		)
		(stroke
			(width 0)
			(type default)
		)
	)
	(wire
		(pts
			(xy 257.81 180.34) (xy 256.54 180.34)
		)
		(stroke
			(width 0)
			(type default)
		)
	)
	(wire
		(pts
			(xy 317.5 41.91) (xy 322.58 41.91)
		)
		(stroke
			(width 0)
			(type default)
		)
	)
	(wire
		(pts
			(xy 111.76 265.43) (xy 111.76 271.78)
		)
		(stroke
			(width 0)
			(type default)
		)
	)
	(wire
		(pts
			(xy 322.58 166.37) (xy 322.58 176.53)
		)
		(stroke
			(width 0)
			(type default)
		)
	)
	(wire
		(pts
			(xy 105.41 217.17) (xy 102.87 217.17)
		)
		(stroke
			(width 0)
			(type default)
		)
	)
	(polyline
		(pts
			(xy 182.88 12.7) (xy 182.88 86.36)
		)
		(stroke
			(width 0)
			(type default)
		)
	)
	(wire
		(pts
			(xy 372.11 219.71) (xy 372.11 217.17)
		)
		(stroke
			(width 0)
			(type default)
		)
	)
	(wire
		(pts
			(xy 236.22 229.87) (xy 257.81 229.87)
		)
		(stroke
			(width 0)
			(type default)
		)
	)
	(wire
		(pts
			(xy 275.59 175.26) (xy 289.56 175.26)
		)
		(stroke
			(width 0)
			(type default)
		)
	)
	(wire
		(pts
			(xy 53.34 184.15) (xy 53.34 186.69)
		)
		(stroke
			(width 0)
			(type default)
		)
	)
	(wire
		(pts
			(xy 176.53 256.54) (xy 177.8 256.54)
		)
		(stroke
			(width 0)
			(type default)
		)
	)
	(wire
		(pts
			(xy 177.8 269.24) (xy 177.8 275.59)
		)
		(stroke
			(width 0)
			(type default)
		)
	)
	(wire
		(pts
			(xy 146.05 171.45) (xy 168.91 171.45)
		)
		(stroke
			(width 0)
			(type default)
		)
	)
	(wire
		(pts
			(xy 78.74 80.01) (xy 76.2 80.01)
		)
		(stroke
			(width 0)
			(type default)
		)
	)
	(wire
		(pts
			(xy 50.8 170.18) (xy 50.8 167.64)
		)
		(stroke
			(width 0)
			(type default)
		)
	)
	(wire
		(pts
			(xy 146.05 190.5) (xy 168.91 190.5)
		)
		(stroke
			(width 0)
			(type default)
		)
	)
	(wire
		(pts
			(xy 146.05 133.35) (xy 167.64 133.35)
		)
		(stroke
			(width 0)
			(type default)
		)
	)
	(wire
		(pts
			(xy 52.07 148.59) (xy 52.07 149.86)
		)
		(stroke
			(width 0)
			(type default)
		)
	)
	(wire
		(pts
			(xy 269.24 67.31) (xy 269.24 68.58)
		)
		(stroke
			(width 0)
			(type default)
		)
	)
	(wire
		(pts
			(xy 143.51 62.23) (xy 143.51 63.5)
		)
		(stroke
			(width 0)
			(type default)
		)
	)
	(wire
		(pts
			(xy 146.05 160.02) (xy 173.99 160.02)
		)
		(stroke
			(width 0)
			(type default)
		)
	)
	(wire
		(pts
			(xy 276.86 210.82) (xy 276.86 212.09)
		)
		(stroke
			(width 0)
			(type default)
		)
	)
	(label "AUX.TDO"
		(at 194.31 152.4 180)
		(effects
			(font
				(size 1.27 1.27)
			)
			(justify right bottom)
		)
	)
	(label "FTDI_PWREN"
		(at 190.5 254 180)
		(effects
			(font
				(size 1.27 1.27)
			)
			(justify right bottom)
		)
	)
	(label "FTDI_3V3"
		(at 363.22 158.75 0)
		(effects
			(font
				(size 1.27 1.27)
			)
			(justify left bottom)
		)
	)
	(label "FTDI_SCL"
		(at 276.86 170.18 0)
		(effects
			(font
				(size 1.27 1.27)
			)
			(justify left bottom)
		)
	)
	(label "VBUS"
		(at 198.12 57.15 0)
		(effects
			(font
				(size 1.27 1.27)
			)
			(justify left bottom)
		)
	)
	(label "VBUS"
		(at 63.5 39.37 0)
		(effects
			(font
				(size 1.27 1.27)
			)
			(justify left bottom)
		)
	)
	(label "BDBUS3"
		(at 311.15 165.1 180)
		(effects
			(font
				(size 1.27 1.27)
			)
			(justify right bottom)
		)
	)
	(label "FTDI_EECLK"
		(at 90.17 172.72 0)
		(effects
			(font
				(size 1.27 1.27)
			)
			(justify left bottom)
		)
	)
	(label "FTDI_EEDAT"
		(at 190.5 264.16 180)
		(effects
			(font
				(size 1.27 1.27)
			)
			(justify right bottom)
		)
	)
	(label "BDBUS2"
		(at 241.3 177.8 0)
		(effects
			(font
				(size 1.27 1.27)
			)
			(justify left bottom)
		)
	)
	(label "FTDI.SDA"
		(at 339.09 176.53 180)
		(effects
			(font
				(size 1.27 1.27)
			)
			(justify right bottom)
		)
	)
	(label "FTDI_3V3"
		(at 364.49 133.35 0)
		(effects
			(font
				(size 1.27 1.27)
			)
			(justify left bottom)
		)
	)
	(label "FTDI_3V3"
		(at 236.22 203.2 0)
		(effects
			(font
				(size 1.27 1.27)
			)
			(justify left bottom)
		)
	)
	(label "JTAG.TCK"
		(at 339.09 140.97 180)
		(effects
			(font
				(size 1.27 1.27)
			)
			(justify right bottom)
		)
	)
	(label "BDBUS0"
		(at 154.94 147.32 180)
		(effects
			(font
				(size 1.27 1.27)
			)
			(justify right bottom)
		)
	)
	(label "AUX.TCK"
		(at 194.31 147.32 180)
		(effects
			(font
				(size 1.27 1.27)
			)
			(justify right bottom)
		)
	)
	(label "FTDI_UART0_TX"
		(at 236.22 208.28 0)
		(effects
			(font
				(size 1.27 1.27)
			)
			(justify left bottom)
		)
	)
	(label "LED_TX0"
		(at 147.32 259.08 0)
		(effects
			(font
				(size 1.27 1.27)
			)
			(justify left bottom)
		)
	)
	(label "FTDI_EECS"
		(at 90.17 170.18 0)
		(effects
			(font
				(size 1.27 1.27)
			)
			(justify left bottom)
		)
	)
	(label "FTDI_VPHY"
		(at 71.12 148.59 180)
		(effects
			(font
				(size 1.27 1.27)
			)
			(justify right bottom)
		)
	)
	(label "FTDI_PWREN"
		(at 248.92 48.26 0)
		(effects
			(font
				(size 1.27 1.27)
			)
			(justify left bottom)
		)
	)
	(label "BDBUS2"
		(at 154.94 152.4 180)
		(effects
			(font
				(size 1.27 1.27)
			)
			(justify right bottom)
		)
	)
	(label "FTDI_JTAG_TMS"
		(at 167.64 133.35 180)
		(effects
			(font
				(size 1.27 1.27)
			)
			(justify right bottom)
		)
	)
	(label "FTDI_SDA_IN"
		(at 276.86 177.8 0)
		(effects
			(font
				(size 1.27 1.27)
			)
			(justify left bottom)
		)
	)
	(label "FTDI_VCORE"
		(at 90.17 140.97 0)
		(effects
			(font
				(size 1.27 1.27)
			)
			(justify left bottom)
		)
	)
	(label "FTDI.SCL"
		(at 339.09 170.18 180)
		(effects
			(font
				(size 1.27 1.27)
			)
			(justify right bottom)
		)
	)
	(label "FTDI_3V3"
		(at 242.57 133.35 0)
		(effects
			(font
				(size 1.27 1.27)
			)
			(justify left bottom)
		)
	)
	(label "FTDI_JTAG_TMS"
		(at 242.57 138.43 0)
		(effects
			(font
				(size 1.27 1.27)
			)
			(justify left bottom)
		)
	)
	(label "DBG_USB_P"
		(at 77.47 52.07 180)
		(effects
			(font
				(size 1.27 1.27)
			)
			(justify right bottom)
		)
	)
	(label "FTDI_UART0_TX"
		(at 168.91 168.91 180)
		(effects
			(font
				(size 1.27 1.27)
			)
			(justify right bottom)
		)
	)
	(label "UART1.TX"
		(at 335.28 227.33 180)
		(effects
			(font
				(size 1.27 1.27)
			)
			(justify right bottom)
		)
	)
	(label "FTDI_3V3"
		(at 33.02 167.64 0)
		(effects
			(font
				(size 1.27 1.27)
			)
			(justify left bottom)
		)
	)
	(label "FTDI_3V3"
		(at 33.02 127 0)
		(effects
			(font
				(size 1.27 1.27)
			)
			(justify left bottom)
		)
	)
	(label "CC1"
		(at 153.67 59.69 180)
		(effects
			(font
				(size 1.27 1.27)
			)
			(justify right bottom)
		)
	)
	(label "AUX.TDI"
		(at 194.31 149.86 180)
		(effects
			(font
				(size 1.27 1.27)
			)
			(justify right bottom)
		)
	)
	(label "FTDI_VPHY"
		(at 90.17 135.89 0)
		(effects
			(font
				(size 1.27 1.27)
			)
			(justify left bottom)
		)
	)
	(label "FTDI_EECLK"
		(at 190.5 259.08 180)
		(effects
			(font
				(size 1.27 1.27)
			)
			(justify right bottom)
		)
	)
	(label "FTDI_UART0_RX"
		(at 236.22 205.74 0)
		(effects
			(font
				(size 1.27 1.27)
			)
			(justify left bottom)
		)
	)
	(label "FTDI_VPLL"
		(at 69.85 167.64 180)
		(effects
			(font
				(size 1.27 1.27)
			)
			(justify right bottom)
		)
	)
	(label "DBG_USB_N"
		(at 77.47 54.61 180)
		(effects
			(font
				(size 1.27 1.27)
			)
			(justify right bottom)
		)
	)
	(label "FTDI_3V3"
		(at 236.22 224.79 0)
		(effects
			(font
				(size 1.27 1.27)
			)
			(justify left bottom)
		)
	)
	(label "FTDI_3V3"
		(at 243.84 57.15 180)
		(effects
			(font
				(size 1.27 1.27)
			)
			(justify right bottom)
		)
	)
	(label "FTDI_JTAG_TDO"
		(at 242.57 146.05 0)
		(effects
			(font
				(size 1.27 1.27)
			)
			(justify left bottom)
		)
	)
	(label "JTAG.TMS"
		(at 339.09 138.43 180)
		(effects
			(font
				(size 1.27 1.27)
			)
			(justify right bottom)
		)
	)
	(label "JTAG.TDI"
		(at 339.09 143.51 180)
		(effects
			(font
				(size 1.27 1.27)
			)
			(justify right bottom)
		)
	)
	(label "CC1"
		(at 63.5 44.45 0)
		(effects
			(font
				(size 1.27 1.27)
			)
			(justify left bottom)
		)
	)
	(label "FTDI_JTAG_TCK"
		(at 167.64 125.73 180)
		(effects
			(font
				(size 1.27 1.27)
			)
			(justify right bottom)
		)
	)
	(label "FTDI_JTAG_TDI"
		(at 167.64 128.27 180)
		(effects
			(font
				(size 1.27 1.27)
			)
			(justify right bottom)
		)
	)
	(label "I2C_EN"
		(at 154.94 160.02 180)
		(effects
			(font
				(size 1.27 1.27)
			)
			(justify right bottom)
		)
	)
	(label "FTDI_UART1_RX"
		(at 236.22 227.33 0)
		(effects
			(font
				(size 1.27 1.27)
			)
			(justify left bottom)
		)
	)
	(label "FTDI_XO"
		(at 97.79 185.42 0)
		(effects
			(font
				(size 1.27 1.27)
			)
			(justify left bottom)
		)
	)
	(label "DBG_USB_N"
		(at 90.17 151.13 0)
		(effects
			(font
				(size 1.27 1.27)
			)
			(justify left bottom)
		)
	)
	(label "FTDI_UART1_TX"
		(at 236.22 229.87 0)
		(effects
			(font
				(size 1.27 1.27)
			)
			(justify left bottom)
		)
	)
	(label "FTDI_UART1_TX"
		(at 168.91 190.5 180)
		(effects
			(font
				(size 1.27 1.27)
			)
			(justify right bottom)
		)
	)
	(label "UART0.TX"
		(at 335.28 205.74 180)
		(effects
			(font
				(size 1.27 1.27)
			)
			(justify right bottom)
		)
	)
	(label "FTDI_JTAG_TDO"
		(at 167.64 130.81 180)
		(effects
			(font
				(size 1.27 1.27)
			)
			(justify right bottom)
		)
	)
	(label "CC2"
		(at 63.5 46.99 0)
		(effects
			(font
				(size 1.27 1.27)
			)
			(justify left bottom)
		)
	)
	(label "UART1.RX"
		(at 335.28 229.87 180)
		(effects
			(font
				(size 1.27 1.27)
			)
			(justify right bottom)
		)
	)
	(label "FTDI_VPLL"
		(at 90.17 138.43 0)
		(effects
			(font
				(size 1.27 1.27)
			)
			(justify left bottom)
		)
	)
	(label "FTDI_JTAG_RST"
		(at 166.37 138.43 180)
		(effects
			(font
				(size 1.27 1.27)
			)
			(justify right bottom)
		)
	)
	(label "I2C_EN"
		(at 311.15 167.64 180)
		(effects
			(font
				(size 1.27 1.27)
			)
			(justify right bottom)
		)
	)
	(label "FTDI_EEDAT"
		(at 90.17 175.26 0)
		(effects
			(font
				(size 1.27 1.27)
			)
			(justify left bottom)
		)
	)
	(label "DBG_USB_N"
		(at 153.67 57.15 180)
		(effects
			(font
				(size 1.27 1.27)
			)
			(justify right bottom)
		)
	)
	(label "FTDI_3V3"
		(at 283.21 38.1 180)
		(effects
			(font
				(size 1.27 1.27)
			)
			(justify right bottom)
		)
	)
	(label "FTDI_3V3"
		(at 90.17 125.73 0)
		(effects
			(font
				(size 1.27 1.27)
			)
			(justify left bottom)
		)
	)
	(label "FTDI_UART0_RX"
		(at 168.91 171.45 180)
		(effects
			(font
				(size 1.27 1.27)
			)
			(justify right bottom)
		)
	)
	(label "FTDI_EECS"
		(at 190.5 261.62 180)
		(effects
			(font
				(size 1.27 1.27)
			)
			(justify right bottom)
		)
	)
	(label "BDBUS3"
		(at 154.94 154.94 180)
		(effects
			(font
				(size 1.27 1.27)
			)
			(justify right bottom)
		)
	)
	(label "DBG_USB_P"
		(at 153.67 54.61 180)
		(effects
			(font
				(size 1.27 1.27)
			)
			(justify right bottom)
		)
	)
	(label "FTDI_3V3"
		(at 209.55 243.84 180)
		(effects
			(font
				(size 1.27 1.27)
			)
			(justify right bottom)
		)
	)
	(label "AUX.RST"
		(at 194.31 160.02 180)
		(effects
			(font
				(size 1.27 1.27)
			)
			(justify right bottom)
		)
	)
	(label "FTDI_JTAG_TCK"
		(at 242.57 140.97 0)
		(effects
			(font
				(size 1.27 1.27)
			)
			(justify left bottom)
		)
	)
	(label "FTDI_3V3"
		(at 363.22 217.17 0)
		(effects
			(font
				(size 1.27 1.27)
			)
			(justify left bottom)
		)
	)
	(label "FTDI_3V3"
		(at 33.02 148.59 0)
		(effects
			(font
				(size 1.27 1.27)
			)
			(justify left bottom)
		)
	)
	(label "FTDI_3V3"
		(at 241.3 165.1 0)
		(effects
			(font
				(size 1.27 1.27)
			)
			(justify left bottom)
		)
	)
	(label "BDBUS1"
		(at 241.3 175.26 0)
		(effects
			(font
				(size 1.27 1.27)
			)
			(justify left bottom)
		)
	)
	(label "FTDI_VCORE"
		(at 33.02 184.15 0)
		(effects
			(font
				(size 1.27 1.27)
			)
			(justify left bottom)
		)
	)
	(label "AUX.TMS"
		(at 194.31 154.94 180)
		(effects
			(font
				(size 1.27 1.27)
			)
			(justify right bottom)
		)
	)
	(label "FTDI_UART1_RX"
		(at 168.91 193.04 180)
		(effects
			(font
				(size 1.27 1.27)
			)
			(justify right bottom)
		)
	)
	(label "FTDI_SDA_OUT"
		(at 276.86 175.26 0)
		(effects
			(font
				(size 1.27 1.27)
			)
			(justify left bottom)
		)
	)
	(label "BDBUS1"
		(at 154.94 149.86 180)
		(effects
			(font
				(size 1.27 1.27)
			)
			(justify right bottom)
		)
	)
	(label "FTDI_3V3"
		(at 363.22 198.12 0)
		(effects
			(font
				(size 1.27 1.27)
			)
			(justify left bottom)
		)
	)
	(label "FTDI_XI"
		(at 97.79 180.34 0)
		(effects
			(font
				(size 1.27 1.27)
			)
			(justify left bottom)
		)
	)
	(label "LED_RX1"
		(at 147.32 266.7 0)
		(effects
			(font
				(size 1.27 1.27)
			)
			(justify left bottom)
		)
	)
	(label "LED_RX0"
		(at 147.32 261.62 0)
		(effects
			(font
				(size 1.27 1.27)
			)
			(justify left bottom)
		)
	)
	(label "LED_TX1"
		(at 147.32 264.16 0)
		(effects
			(font
				(size 1.27 1.27)
			)
			(justify left bottom)
		)
	)
	(label "DBG_USB_P"
		(at 90.17 148.59 0)
		(effects
			(font
				(size 1.27 1.27)
			)
			(justify left bottom)
		)
	)
	(label "FTDI_JTAG_TDI"
		(at 242.57 143.51 0)
		(effects
			(font
				(size 1.27 1.27)
			)
			(justify left bottom)
		)
	)
	(label "JTAG.TDO"
		(at 339.09 146.05 180)
		(effects
			(font
				(size 1.27 1.27)
			)
			(justify right bottom)
		)
	)
	(label "CC2"
		(at 153.67 52.07 180)
		(effects
			(font
				(size 1.27 1.27)
			)
			(justify right bottom)
		)
	)
	(label "BDBUS0"
		(at 241.3 170.18 0)
		(effects
			(font
				(size 1.27 1.27)
			)
			(justify left bottom)
		)
	)
	(label "FTDI_PWREN"
		(at 158.75 213.36 180)
		(effects
			(font
				(size 1.27 1.27)
			)
			(justify right bottom)
		)
	)
	(label "UART0.RX"
		(at 335.28 208.28 180)
		(effects
			(font
				(size 1.27 1.27)
			)
			(justify right bottom)
		)
	)
	(label "FTDI_3V3"
		(at 90.17 162.56 0)
		(effects
			(font
				(size 1.27 1.27)
			)
			(justify left bottom)
		)
	)
	(global_label "FTDI_DIS"
		(shape input)
		(at 297.18 133.35 0)
		(fields_autoplaced yes)
		(effects
			(font
				(size 1.27 1.27)
			)
			(justify left)
		)
		(property "Intersheetrefs" "${INTERSHEET_REFS}"
			(at 307.576 133.4294 0)
			(effects
				(font
					(size 1.27 1.27)
				)
				(justify left)
			)
		)
	)
	(hierarchical_label "FTDI{I^{2}C}"
		(shape bidirectional)
		(at 345.44 163.83 0)
		(effects
			(font
				(size 1.27 1.27)
			)
			(justify left)
		)
	)
	(hierarchical_label "UART1{UART}"
		(shape bidirectional)
		(at 345.44 220.98 0)
		(effects
			(font
				(size 1.27 1.27)
			)
			(justify left)
		)
	)
	(hierarchical_label "JTAG{JTAG}"
		(shape bidirectional)
		(at 345.44 133.35 0)
		(effects
			(font
				(size 1.27 1.27)
			)
			(justify left)
		)
	)
	(hierarchical_label "UART0{UART}"
		(shape bidirectional)
		(at 345.44 199.39 0)
		(effects
			(font
				(size 1.27 1.27)
			)
			(justify left)
		)
	)
	(hierarchical_label "AUX{JTAG}"
		(shape bidirectional)
		(at 200.66 142.24 0)
		(effects
			(font
				(size 1.27 1.27)
			)
			(justify left)
		)
	)
	(symbol
		(lib_id "antmicroResistors0402:R_22R_0402")
		(at 284.48 205.74 0)
		(unit 1)
		(exclude_from_sim no)
		(in_bom yes)
		(on_board yes)
		(dnp no)
		(property "Reference" "R52"
			(at 292.1 204.47 0)
			(effects
				(font
					(size 1.27 1.27)
				)
			)
		)
		(property "Value" "R_22R_0402"
			(at 304.8 218.44 0)
			(effects
				(font
					(size 1.27 1.27)
					(thickness 0.15)
				)
				(justify left bottom)
				(hide yes)
			)
		)
		(property "Footprint" "antmicro-footprints:R_0402_1005Metric"
			(at 304.8 220.98 0)
			(effects
				(font
					(size 1.27 1.27)
					(thickness 0.15)
				)
				(justify left bottom)
				(hide yes)
			)
		)
		(property "Datasheet" "https://www.bourns.com/docs/product-datasheets/cr.pdf"
			(at 304.8 223.52 0)
			(effects
				(font
					(size 1.27 1.27)
					(thickness 0.15)
				)
				(justify left bottom)
				(hide yes)
			)
		)
		(property "Description" ""
			(at 284.48 205.74 0)
			(effects
				(font
					(size 1.27 1.27)
				)
				(hide yes)
			)
		)
		(property "Manufacturer" "Bourns"
			(at 304.8 228.6 0)
			(effects
				(font
					(size 1.27 1.27)
					(thickness 0.15)
				)
				(justify left bottom)
				(hide yes)
			)
		)
		(property "MPN" "CR0402-FX-22R0GLF"
			(at 304.8 226.06 0)
			(effects
				(font
					(size 1.27 1.27)
					(thickness 0.15)
				)
				(justify left bottom)
				(hide yes)
			)
		)
		(property "Val" "22R"
			(at 282.575 204.47 0)
			(effects
				(font
					(size 1.27 1.27)
					(thickness 0.15)
				)
			)
		)
		(property "License" "Apache-2.0"
			(at 304.8 231.14 0)
			(effects
				(font
					(size 1.27 1.27)
					(thickness 0.15)
				)
				(justify left bottom)
				(hide yes)
			)
		)
		(property "Author" "Antmicro"
			(at 304.8 233.68 0)
			(effects
				(font
					(size 1.27 1.27)
					(thickness 0.15)
				)
				(justify left bottom)
				(hide yes)
			)
		)
		(property "Tolerance" "1%"
			(at 304.8 215.9 0)
			(effects
				(font
					(size 1.27 1.27)
				)
				(justify left bottom)
				(hide yes)
			)
		)
		(pin "1"
		)
		(pin "2"
		)
		(instances
			(project "data-center-rdimm-ddr5-tester"
				(path ""
					(reference "R52")
					(unit 1)
				)
			)
		)
	)
	(symbol
		(lib_id "antmicroResistors0402:R_22R_0402")
		(at 284.48 229.87 0)
		(unit 1)
		(exclude_from_sim no)
		(in_bom yes)
		(on_board yes)
		(dnp no)
		(property "Reference" "R55"
			(at 291.465 228.6 0)
			(effects
				(font
					(size 1.27 1.27)
				)
			)
		)
		(property "Value" "R_22R_0402"
			(at 304.8 242.57 0)
			(effects
				(font
					(size 1.27 1.27)
					(thickness 0.15)
				)
				(justify left bottom)
				(hide yes)
			)
		)
		(property "Footprint" "antmicro-footprints:R_0402_1005Metric"
			(at 304.8 245.11 0)
			(effects
				(font
					(size 1.27 1.27)
					(thickness 0.15)
				)
				(justify left bottom)
				(hide yes)
			)
		)
		(property "Datasheet" "https://www.bourns.com/docs/product-datasheets/cr.pdf"
			(at 304.8 247.65 0)
			(effects
				(font
					(size 1.27 1.27)
					(thickness 0.15)
				)
				(justify left bottom)
				(hide yes)
			)
		)
		(property "Description" ""
			(at 284.48 229.87 0)
			(effects
				(font
					(size 1.27 1.27)
				)
				(hide yes)
			)
		)
		(property "Manufacturer" "Bourns"
			(at 304.8 252.73 0)
			(effects
				(font
					(size 1.27 1.27)
					(thickness 0.15)
				)
				(justify left bottom)
				(hide yes)
			)
		)
		(property "MPN" "CR0402-FX-22R0GLF"
			(at 304.8 250.19 0)
			(effects
				(font
					(size 1.27 1.27)
					(thickness 0.15)
				)
				(justify left bottom)
				(hide yes)
			)
		)
		(property "Val" "22R"
			(at 282.575 228.6 0)
			(effects
				(font
					(size 1.27 1.27)
					(thickness 0.15)
				)
			)
		)
		(property "License" "Apache-2.0"
			(at 304.8 255.27 0)
			(effects
				(font
					(size 1.27 1.27)
					(thickness 0.15)
				)
				(justify left bottom)
				(hide yes)
			)
		)
		(property "Author" "Antmicro"
			(at 304.8 257.81 0)
			(effects
				(font
					(size 1.27 1.27)
					(thickness 0.15)
				)
				(justify left bottom)
				(hide yes)
			)
		)
		(property "Tolerance" "1%"
			(at 304.8 240.03 0)
			(effects
				(font
					(size 1.27 1.27)
				)
				(justify left bottom)
				(hide yes)
			)
		)
		(pin "1"
		)
		(pin "2"
		)
		(instances
			(project "data-center-rdimm-ddr5-tester"
				(path ""
					(reference "R55")
					(unit 1)
				)
			)
		)
	)
	(symbol
		(lib_id "antmicroResistors0402:R_22R_0402")
		(at 284.48 208.28 0)
		(unit 1)
		(exclude_from_sim no)
		(in_bom yes)
		(on_board yes)
		(dnp no)
		(property "Reference" "R53"
			(at 292.1 207.01 0)
			(effects
				(font
					(size 1.27 1.27)
				)
			)
		)
		(property "Value" "R_22R_0402"
			(at 304.8 220.98 0)
			(effects
				(font
					(size 1.27 1.27)
					(thickness 0.15)
				)
				(justify left bottom)
				(hide yes)
			)
		)
		(property "Footprint" "antmicro-footprints:R_0402_1005Metric"
			(at 304.8 223.52 0)
			(effects
				(font
					(size 1.27 1.27)
					(thickness 0.15)
				)
				(justify left bottom)
				(hide yes)
			)
		)
		(property "Datasheet" "https://www.bourns.com/docs/product-datasheets/cr.pdf"
			(at 304.8 226.06 0)
			(effects
				(font
					(size 1.27 1.27)
					(thickness 0.15)
				)
				(justify left bottom)
				(hide yes)
			)
		)
		(property "Description" ""
			(at 284.48 208.28 0)
			(effects
				(font
					(size 1.27 1.27)
				)
				(hide yes)
			)
		)
		(property "Manufacturer" "Bourns"
			(at 304.8 231.14 0)
			(effects
				(font
					(size 1.27 1.27)
					(thickness 0.15)
				)
				(justify left bottom)
				(hide yes)
			)
		)
		(property "MPN" "CR0402-FX-22R0GLF"
			(at 304.8 228.6 0)
			(effects
				(font
					(size 1.27 1.27)
					(thickness 0.15)
				)
				(justify left bottom)
				(hide yes)
			)
		)
		(property "Val" "22R"
			(at 282.575 207.01 0)
			(effects
				(font
					(size 1.27 1.27)
					(thickness 0.15)
				)
			)
		)
		(property "License" "Apache-2.0"
			(at 304.8 233.68 0)
			(effects
				(font
					(size 1.27 1.27)
					(thickness 0.15)
				)
				(justify left bottom)
				(hide yes)
			)
		)
		(property "Author" "Antmicro"
			(at 304.8 236.22 0)
			(effects
				(font
					(size 1.27 1.27)
					(thickness 0.15)
				)
				(justify left bottom)
				(hide yes)
			)
		)
		(property "Tolerance" "1%"
			(at 304.8 218.44 0)
			(effects
				(font
					(size 1.27 1.27)
				)
				(justify left bottom)
				(hide yes)
			)
		)
		(pin "1"
		)
		(pin "2"
		)
		(instances
			(project "data-center-rdimm-ddr5-tester"
				(path ""
					(reference "R53")
					(unit 1)
				)
			)
		)
	)
	(symbol
		(lib_id "antmicroResistors0402:R_22R_0402")
		(at 284.48 227.33 0)
		(unit 1)
		(exclude_from_sim no)
		(in_bom yes)
		(on_board yes)
		(dnp no)
		(property "Reference" "R54"
			(at 291.465 226.06 0)
			(effects
				(font
					(size 1.27 1.27)
				)
			)
		)
		(property "Value" "R_22R_0402"
			(at 304.8 240.03 0)
			(effects
				(font
					(size 1.27 1.27)
					(thickness 0.15)
				)
				(justify left bottom)
				(hide yes)
			)
		)
		(property "Footprint" "antmicro-footprints:R_0402_1005Metric"
			(at 304.8 242.57 0)
			(effects
				(font
					(size 1.27 1.27)
					(thickness 0.15)
				)
				(justify left bottom)
				(hide yes)
			)
		)
		(property "Datasheet" "https://www.bourns.com/docs/product-datasheets/cr.pdf"
			(at 304.8 245.11 0)
			(effects
				(font
					(size 1.27 1.27)
					(thickness 0.15)
				)
				(justify left bottom)
				(hide yes)
			)
		)
		(property "Description" ""
			(at 284.48 227.33 0)
			(effects
				(font
					(size 1.27 1.27)
				)
				(hide yes)
			)
		)
		(property "Manufacturer" "Bourns"
			(at 304.8 250.19 0)
			(effects
				(font
					(size 1.27 1.27)
					(thickness 0.15)
				)
				(justify left bottom)
				(hide yes)
			)
		)
		(property "MPN" "CR0402-FX-22R0GLF"
			(at 304.8 247.65 0)
			(effects
				(font
					(size 1.27 1.27)
					(thickness 0.15)
				)
				(justify left bottom)
				(hide yes)
			)
		)
		(property "Val" "22R"
			(at 282.575 226.06 0)
			(effects
				(font
					(size 1.27 1.27)
					(thickness 0.15)
				)
			)
		)
		(property "License" "Apache-2.0"
			(at 304.8 252.73 0)
			(effects
				(font
					(size 1.27 1.27)
					(thickness 0.15)
				)
				(justify left bottom)
				(hide yes)
			)
		)
		(property "Author" "Antmicro"
			(at 304.8 255.27 0)
			(effects
				(font
					(size 1.27 1.27)
					(thickness 0.15)
				)
				(justify left bottom)
				(hide yes)
			)
		)
		(property "Tolerance" "1%"
			(at 304.8 237.49 0)
			(effects
				(font
					(size 1.27 1.27)
				)
				(justify left bottom)
				(hide yes)
			)
		)
		(pin "1"
		)
		(pin "2"
		)
		(instances
			(project "data-center-rdimm-ddr5-tester"
				(path ""
					(reference "R54")
					(unit 1)
				)
			)
		)
	)
	(symbol
		(lib_id "antmicroCapacitors0402:C_100n_0402")
		(at 60.96 149.86 270)
		(unit 1)
		(exclude_from_sim no)
		(in_bom yes)
		(on_board yes)
		(dnp no)
		(property "Reference" "C112"
			(at 61.595 150.495 90)
			(effects
				(font
					(size 1.27 1.27)
				)
				(justify left)
			)
		)
		(property "Value" "C_100n_0402"
			(at 50.8 170.18 0)
			(effects
				(font
					(size 1.27 1.27)
					(thickness 0.15)
				)
				(justify left bottom)
				(hide yes)
			)
		)
		(property "Footprint" "antmicro-footprints:C_0402_1005Metric"
			(at 48.26 170.18 0)
			(effects
				(font
					(size 1.27 1.27)
					(thickness 0.15)
				)
				(justify left bottom)
				(hide yes)
			)
		)
		(property "Datasheet" "https://www.murata.com/products/productdetail?partno=GRM155R61H104KE14%23"
			(at 45.72 170.18 0)
			(effects
				(font
					(size 1.27 1.27)
					(thickness 0.15)
				)
				(justify left bottom)
				(hide yes)
			)
		)
		(property "Description" ""
			(at 60.96 149.86 0)
			(effects
				(font
					(size 1.27 1.27)
				)
				(hide yes)
			)
		)
		(property "Manufacturer" "Murata"
			(at 40.64 170.18 0)
			(effects
				(font
					(size 1.27 1.27)
					(thickness 0.15)
				)
				(justify left bottom)
				(hide yes)
			)
		)
		(property "MPN" "GRM155R61H104KE14D"
			(at 43.18 170.18 0)
			(effects
				(font
					(size 1.27 1.27)
					(thickness 0.15)
				)
				(justify left bottom)
				(hide yes)
			)
		)
		(property "Val" "100n"
			(at 61.595 154.305 90)
			(effects
				(font
					(size 1.27 1.27)
					(thickness 0.15)
				)
				(justify left)
			)
		)
		(property "License" "Apache-2.0"
			(at 38.1 170.18 0)
			(effects
				(font
					(size 1.27 1.27)
					(thickness 0.15)
				)
				(justify left bottom)
				(hide yes)
			)
		)
		(property "Author" "Antmicro"
			(at 35.56 170.18 0)
			(effects
				(font
					(size 1.27 1.27)
					(thickness 0.15)
				)
				(justify left bottom)
				(hide yes)
			)
		)
		(property "Voltage" "50V"
			(at 33.02 170.18 0)
			(effects
				(font
					(size 1.27 1.27)
				)
				(justify left bottom)
				(hide yes)
			)
		)
		(property "Dielectric" "X5R"
			(at 30.48 170.18 0)
			(effects
				(font
					(size 1.27 1.27)
				)
				(justify left bottom)
				(hide yes)
			)
		)
		(pin "1"
		)
		(pin "2"
		)
		(instances
			(project "data-center-rdimm-ddr5-tester"
				(path ""
					(reference "C112")
					(unit 1)
				)
			)
		)
	)
	(symbol
		(lib_id "antmicroCapacitors0402:C_4u7_0402")
		(at 52.07 149.86 270)
		(unit 1)
		(exclude_from_sim no)
		(in_bom yes)
		(on_board yes)
		(dnp no)
		(property "Reference" "C116"
			(at 57.785 150.495 90)
			(effects
				(font
					(size 1.27 1.27)
				)
				(justify right)
			)
		)
		(property "Value" "C_4u7_0402"
			(at 41.91 170.18 0)
			(effects
				(font
					(size 1.27 1.27)
					(thickness 0.15)
				)
				(justify left bottom)
				(hide yes)
			)
		)
		(property "Footprint" "antmicro-footprints:C_0402_1005Metric"
			(at 39.37 170.18 0)
			(effects
				(font
					(size 1.27 1.27)
					(thickness 0.15)
				)
				(justify left bottom)
				(hide yes)
			)
		)
		(property "Datasheet" "https://www.murata.com/products/productdetail?partno=GRM155R61A475MEAA%23"
			(at 36.83 170.18 0)
			(effects
				(font
					(size 1.27 1.27)
					(thickness 0.15)
				)
				(justify left bottom)
				(hide yes)
			)
		)
		(property "Description" ""
			(at 52.07 149.86 0)
			(effects
				(font
					(size 1.27 1.27)
				)
				(hide yes)
			)
		)
		(property "Manufacturer" "Murata"
			(at 31.75 170.18 0)
			(effects
				(font
					(size 1.27 1.27)
					(thickness 0.15)
				)
				(justify left bottom)
				(hide yes)
			)
		)
		(property "MPN" "GRM155R61A475MEAAD"
			(at 34.29 170.18 0)
			(effects
				(font
					(size 1.27 1.27)
					(thickness 0.15)
				)
				(justify left bottom)
				(hide yes)
			)
		)
		(property "Val" "4u7"
			(at 56.515 154.305 90)
			(effects
				(font
					(size 1.27 1.27)
					(thickness 0.15)
				)
				(justify right)
			)
		)
		(property "License" "Apache-2.0"
			(at 29.21 170.18 0)
			(effects
				(font
					(size 1.27 1.27)
					(thickness 0.15)
				)
				(justify left bottom)
				(hide yes)
			)
		)
		(property "Author" "Antmicro"
			(at 26.67 170.18 0)
			(effects
				(font
					(size 1.27 1.27)
					(thickness 0.15)
				)
				(justify left bottom)
				(hide yes)
			)
		)
		(property "Voltage" ""
			(at 24.13 170.18 0)
			(effects
				(font
					(size 1.27 1.27)
				)
				(justify left bottom)
				(hide yes)
			)
		)
		(property "Dielectric" ""
			(at 21.59 170.18 0)
			(effects
				(font
					(size 1.27 1.27)
				)
				(justify left bottom)
				(hide yes)
			)
		)
		(pin "1"
		)
		(pin "2"
		)
		(instances
			(project "data-center-rdimm-ddr5-tester"
				(path ""
					(reference "C116")
					(unit 1)
				)
			)
		)
	)
	(symbol
		(lib_id "antmicroCapacitors0402:C_100n_0402")
		(at 59.69 170.18 270)
		(unit 1)
		(exclude_from_sim no)
		(in_bom yes)
		(on_board yes)
		(dnp no)
		(property "Reference" "C110"
			(at 60.325 170.815 90)
			(effects
				(font
					(size 1.27 1.27)
				)
				(justify left)
			)
		)
		(property "Value" "C_100n_0402"
			(at 49.53 190.5 0)
			(effects
				(font
					(size 1.27 1.27)
					(thickness 0.15)
				)
				(justify left bottom)
				(hide yes)
			)
		)
		(property "Footprint" "antmicro-footprints:C_0402_1005Metric"
			(at 46.99 190.5 0)
			(effects
				(font
					(size 1.27 1.27)
					(thickness 0.15)
				)
				(justify left bottom)
				(hide yes)
			)
		)
		(property "Datasheet" "https://www.murata.com/products/productdetail?partno=GRM155R61H104KE14%23"
			(at 44.45 190.5 0)
			(effects
				(font
					(size 1.27 1.27)
					(thickness 0.15)
				)
				(justify left bottom)
				(hide yes)
			)
		)
		(property "Description" ""
			(at 59.69 170.18 0)
			(effects
				(font
					(size 1.27 1.27)
				)
				(hide yes)
			)
		)
		(property "Manufacturer" "Murata"
			(at 39.37 190.5 0)
			(effects
				(font
					(size 1.27 1.27)
					(thickness 0.15)
				)
				(justify left bottom)
				(hide yes)
			)
		)
		(property "MPN" "GRM155R61H104KE14D"
			(at 41.91 190.5 0)
			(effects
				(font
					(size 1.27 1.27)
					(thickness 0.15)
				)
				(justify left bottom)
				(hide yes)
			)
		)
		(property "Val" "100n"
			(at 60.325 174.625 90)
			(effects
				(font
					(size 1.27 1.27)
					(thickness 0.15)
				)
				(justify left)
			)
		)
		(property "License" "Apache-2.0"
			(at 36.83 190.5 0)
			(effects
				(font
					(size 1.27 1.27)
					(thickness 0.15)
				)
				(justify left bottom)
				(hide yes)
			)
		)
		(property "Author" "Antmicro"
			(at 34.29 190.5 0)
			(effects
				(font
					(size 1.27 1.27)
					(thickness 0.15)
				)
				(justify left bottom)
				(hide yes)
			)
		)
		(property "Voltage" "50V"
			(at 31.75 190.5 0)
			(effects
				(font
					(size 1.27 1.27)
				)
				(justify left bottom)
				(hide yes)
			)
		)
		(property "Dielectric" "X5R"
			(at 29.21 190.5 0)
			(effects
				(font
					(size 1.27 1.27)
				)
				(justify left bottom)
				(hide yes)
			)
		)
		(pin "1"
		)
		(pin "2"
		)
		(instances
			(project "data-center-rdimm-ddr5-tester"
				(path ""
					(reference "C110")
					(unit 1)
				)
			)
		)
	)
	(symbol
		(lib_id "antmicroCapacitors0402:C_4u7_0402")
		(at 50.8 170.18 270)
		(unit 1)
		(exclude_from_sim no)
		(in_bom yes)
		(on_board yes)
		(dnp no)
		(property "Reference" "C114"
			(at 51.435 170.815 90)
			(effects
				(font
					(size 1.27 1.27)
				)
				(justify left)
			)
		)
		(property "Value" "C_4u7_0402"
			(at 40.64 190.5 0)
			(effects
				(font
					(size 1.27 1.27)
					(thickness 0.15)
				)
				(justify left bottom)
				(hide yes)
			)
		)
		(property "Footprint" "antmicro-footprints:C_0402_1005Metric"
			(at 38.1 190.5 0)
			(effects
				(font
					(size 1.27 1.27)
					(thickness 0.15)
				)
				(justify left bottom)
				(hide yes)
			)
		)
		(property "Datasheet" "https://www.murata.com/products/productdetail?partno=GRM155R61A475MEAA%23"
			(at 35.56 190.5 0)
			(effects
				(font
					(size 1.27 1.27)
					(thickness 0.15)
				)
				(justify left bottom)
				(hide yes)
			)
		)
		(property "Description" ""
			(at 50.8 170.18 0)
			(effects
				(font
					(size 1.27 1.27)
				)
				(hide yes)
			)
		)
		(property "Manufacturer" "Murata"
			(at 30.48 190.5 0)
			(effects
				(font
					(size 1.27 1.27)
					(thickness 0.15)
				)
				(justify left bottom)
				(hide yes)
			)
		)
		(property "MPN" "GRM155R61A475MEAAD"
			(at 33.02 190.5 0)
			(effects
				(font
					(size 1.27 1.27)
					(thickness 0.15)
				)
				(justify left bottom)
				(hide yes)
			)
		)
		(property "Val" "4u7"
			(at 51.435 174.625 90)
			(effects
				(font
					(size 1.27 1.27)
					(thickness 0.15)
				)
				(justify left)
			)
		)
		(property "License" "Apache-2.0"
			(at 27.94 190.5 0)
			(effects
				(font
					(size 1.27 1.27)
					(thickness 0.15)
				)
				(justify left bottom)
				(hide yes)
			)
		)
		(property "Author" "Antmicro"
			(at 25.4 190.5 0)
			(effects
				(font
					(size 1.27 1.27)
					(thickness 0.15)
				)
				(justify left bottom)
				(hide yes)
			)
		)
		(property "Voltage" ""
			(at 22.86 190.5 0)
			(effects
				(font
					(size 1.27 1.27)
				)
				(justify left bottom)
				(hide yes)
			)
		)
		(property "Dielectric" ""
			(at 20.32 190.5 0)
			(effects
				(font
					(size 1.27 1.27)
				)
				(justify left bottom)
				(hide yes)
			)
		)
		(pin "1"
		)
		(pin "2"
		)
		(instances
			(project "data-center-rdimm-ddr5-tester"
				(path ""
					(reference "C114")
					(unit 1)
				)
			)
		)
	)
	(symbol
		(lib_id "antmicroResistors0402:R_12k_0402")
		(at 102.87 212.09 90)
		(unit 1)
		(exclude_from_sim no)
		(in_bom yes)
		(on_board yes)
		(dnp no)
		(fields_autoplaced yes)
		(property "Reference" "R44"
			(at 100.965 208.28 90)
			(effects
				(font
					(size 1.27 1.27)
				)
				(justify left)
			)
		)
		(property "Value" "R_12k_0402"
			(at 115.57 191.77 0)
			(effects
				(font
					(size 1.27 1.27)
					(thickness 0.15)
				)
				(justify left bottom)
				(hide yes)
			)
		)
		(property "Footprint" "antmicro-footprints:R_0402_1005Metric"
			(at 118.11 191.77 0)
			(effects
				(font
					(size 1.27 1.27)
					(thickness 0.15)
				)
				(justify left bottom)
				(hide yes)
			)
		)
		(property "Datasheet" "https://www.bourns.com/docs/product-datasheets/cr.pdf"
			(at 120.65 191.77 0)
			(effects
				(font
					(size 1.27 1.27)
					(thickness 0.15)
				)
				(justify left bottom)
				(hide yes)
			)
		)
		(property "Description" ""
			(at 102.87 212.09 0)
			(effects
				(font
					(size 1.27 1.27)
				)
				(hide yes)
			)
		)
		(property "Manufacturer" "Bourns"
			(at 125.73 191.77 0)
			(effects
				(font
					(size 1.27 1.27)
					(thickness 0.15)
				)
				(justify left bottom)
				(hide yes)
			)
		)
		(property "MPN" "CR0402-FX-1202GLF"
			(at 123.19 191.77 0)
			(effects
				(font
					(size 1.27 1.27)
					(thickness 0.15)
				)
				(justify left bottom)
				(hide yes)
			)
		)
		(property "Val" "12k"
			(at 100.965 211.4549 90)
			(effects
				(font
					(size 1.27 1.27)
					(thickness 0.15)
				)
				(justify left)
			)
		)
		(property "License" "Apache-2.0"
			(at 128.27 191.77 0)
			(effects
				(font
					(size 1.27 1.27)
					(thickness 0.15)
				)
				(justify left bottom)
				(hide yes)
			)
		)
		(property "Author" "Antmicro"
			(at 130.81 191.77 0)
			(effects
				(font
					(size 1.27 1.27)
					(thickness 0.15)
				)
				(justify left bottom)
				(hide yes)
			)
		)
		(property "Tolerance" "1%"
			(at 113.03 191.77 0)
			(effects
				(font
					(size 1.27 1.27)
				)
				(justify left bottom)
				(hide yes)
			)
		)
		(pin "1"
		)
		(pin "2"
		)
		(instances
			(project "data-center-rdimm-ddr5-tester"
				(path ""
					(reference "R44")
					(unit 1)
				)
			)
		)
	)
	(symbol
		(lib_id "antmicroResistors0402:R_10k_0402")
		(at 99.06 162.56 0)
		(unit 1)
		(exclude_from_sim no)
		(in_bom yes)
		(on_board yes)
		(dnp no)
		(property "Reference" "R43"
			(at 101.6 157.48 0)
			(effects
				(font
					(size 1.27 1.27)
				)
			)
		)
		(property "Value" "R_10k_0402"
			(at 119.38 175.26 0)
			(effects
				(font
					(size 1.27 1.27)
					(thickness 0.15)
				)
				(justify left bottom)
				(hide yes)
			)
		)
		(property "Footprint" "antmicro-footprints:R_0402_1005Metric"
			(at 119.38 177.8 0)
			(effects
				(font
					(size 1.27 1.27)
					(thickness 0.15)
				)
				(justify left bottom)
				(hide yes)
			)
		)
		(property "Datasheet" "https://www.bourns.com/docs/product-datasheets/cr.pdf"
			(at 119.38 180.34 0)
			(effects
				(font
					(size 1.27 1.27)
					(thickness 0.15)
				)
				(justify left bottom)
				(hide yes)
			)
		)
		(property "Description" ""
			(at 99.06 162.56 0)
			(effects
				(font
					(size 1.27 1.27)
				)
				(hide yes)
			)
		)
		(property "Manufacturer" "Bourns"
			(at 119.38 185.42 0)
			(effects
				(font
					(size 1.27 1.27)
					(thickness 0.15)
				)
				(justify left bottom)
				(hide yes)
			)
		)
		(property "MPN" "CR0402-FX-1002GLF"
			(at 119.38 182.88 0)
			(effects
				(font
					(size 1.27 1.27)
					(thickness 0.15)
				)
				(justify left bottom)
				(hide yes)
			)
		)
		(property "Val" "10k"
			(at 101.6 160.02 0)
			(effects
				(font
					(size 1.27 1.27)
					(thickness 0.15)
				)
			)
		)
		(property "License" "Apache-2.0"
			(at 119.38 187.96 0)
			(effects
				(font
					(size 1.27 1.27)
					(thickness 0.15)
				)
				(justify left bottom)
				(hide yes)
			)
		)
		(property "Author" "Antmicro"
			(at 119.38 190.5 0)
			(effects
				(font
					(size 1.27 1.27)
					(thickness 0.15)
				)
				(justify left bottom)
				(hide yes)
			)
		)
		(property "Tolerance" "1%"
			(at 119.38 172.72 0)
			(effects
				(font
					(size 1.27 1.27)
				)
				(justify left bottom)
				(hide yes)
			)
		)
		(pin "1"
		)
		(pin "2"
		)
		(instances
			(project "data-center-rdimm-ddr5-tester"
				(path ""
					(reference "R43")
					(unit 1)
				)
			)
		)
	)
	(symbol
		(lib_id "antmicroCapacitors0402:C_18p_0402")
		(at 76.2 190.5 270)
		(unit 1)
		(exclude_from_sim no)
		(in_bom yes)
		(on_board yes)
		(dnp no)
		(property "Reference" "C111"
			(at 76.835 191.135 90)
			(effects
				(font
					(size 1.27 1.27)
				)
				(justify left)
			)
		)
		(property "Value" "C_18p_0402"
			(at 66.04 210.82 0)
			(effects
				(font
					(size 1.27 1.27)
					(thickness 0.15)
				)
				(justify left bottom)
				(hide yes)
			)
		)
		(property "Footprint" "antmicro-footprints:C_0402_1005Metric"
			(at 63.5 210.82 0)
			(effects
				(font
					(size 1.27 1.27)
					(thickness 0.15)
				)
				(justify left bottom)
				(hide yes)
			)
		)
		(property "Datasheet" "https://product.samsungsem.com/mlcc/CL05C180JB51PN.do"
			(at 60.96 210.82 0)
			(effects
				(font
					(size 1.27 1.27)
					(thickness 0.15)
				)
				(justify left bottom)
				(hide yes)
			)
		)
		(property "Description" ""
			(at 76.2 190.5 0)
			(effects
				(font
					(size 1.27 1.27)
				)
				(hide yes)
			)
		)
		(property "Manufacturer" "Samsung Electro-Mechanics"
			(at 55.88 210.82 0)
			(effects
				(font
					(size 1.27 1.27)
					(thickness 0.15)
				)
				(justify left bottom)
				(hide yes)
			)
		)
		(property "MPN" "CL05C180JB51PNC"
			(at 58.42 210.82 0)
			(effects
				(font
					(size 1.27 1.27)
					(thickness 0.15)
				)
				(justify left bottom)
				(hide yes)
			)
		)
		(property "Val" "18p"
			(at 76.835 194.945 90)
			(effects
				(font
					(size 1.27 1.27)
					(thickness 0.15)
				)
				(justify left)
			)
		)
		(property "License" "Apache-2.0"
			(at 53.34 210.82 0)
			(effects
				(font
					(size 1.27 1.27)
					(thickness 0.15)
				)
				(justify left bottom)
				(hide yes)
			)
		)
		(property "Author" "Antmicro"
			(at 50.8 210.82 0)
			(effects
				(font
					(size 1.27 1.27)
					(thickness 0.15)
				)
				(justify left bottom)
				(hide yes)
			)
		)
		(property "Voltage" ""
			(at 48.26 210.82 0)
			(effects
				(font
					(size 1.27 1.27)
				)
				(justify left bottom)
				(hide yes)
			)
		)
		(property "Dielectric" ""
			(at 45.72 210.82 0)
			(effects
				(font
					(size 1.27 1.27)
				)
				(justify left bottom)
				(hide yes)
			)
		)
		(pin "1"
		)
		(pin "2"
		)
		(instances
			(project "data-center-rdimm-ddr5-tester"
				(path ""
					(reference "C111")
					(unit 1)
				)
			)
		)
	)
	(symbol
		(lib_id "antmicroCapacitors0402:C_18p_0402")
		(at 96.52 190.5 270)
		(unit 1)
		(exclude_from_sim no)
		(in_bom yes)
		(on_board yes)
		(dnp no)
		(property "Reference" "C117"
			(at 97.155 191.135 90)
			(effects
				(font
					(size 1.27 1.27)
				)
				(justify left)
			)
		)
		(property "Value" "C_18p_0402"
			(at 86.36 210.82 0)
			(effects
				(font
					(size 1.27 1.27)
					(thickness 0.15)
				)
				(justify left bottom)
				(hide yes)
			)
		)
		(property "Footprint" "antmicro-footprints:C_0402_1005Metric"
			(at 83.82 210.82 0)
			(effects
				(font
					(size 1.27 1.27)
					(thickness 0.15)
				)
				(justify left bottom)
				(hide yes)
			)
		)
		(property "Datasheet" "https://product.samsungsem.com/mlcc/CL05C180JB51PN.do"
			(at 81.28 210.82 0)
			(effects
				(font
					(size 1.27 1.27)
					(thickness 0.15)
				)
				(justify left bottom)
				(hide yes)
			)
		)
		(property "Description" ""
			(at 96.52 190.5 0)
			(effects
				(font
					(size 1.27 1.27)
				)
				(hide yes)
			)
		)
		(property "Manufacturer" "Samsung Electro-Mechanics"
			(at 76.2 210.82 0)
			(effects
				(font
					(size 1.27 1.27)
					(thickness 0.15)
				)
				(justify left bottom)
				(hide yes)
			)
		)
		(property "MPN" "CL05C180JB51PNC"
			(at 78.74 210.82 0)
			(effects
				(font
					(size 1.27 1.27)
					(thickness 0.15)
				)
				(justify left bottom)
				(hide yes)
			)
		)
		(property "Val" "18p"
			(at 97.155 194.945 90)
			(effects
				(font
					(size 1.27 1.27)
					(thickness 0.15)
				)
				(justify left)
			)
		)
		(property "License" "Apache-2.0"
			(at 73.66 210.82 0)
			(effects
				(font
					(size 1.27 1.27)
					(thickness 0.15)
				)
				(justify left bottom)
				(hide yes)
			)
		)
		(property "Author" "Antmicro"
			(at 71.12 210.82 0)
			(effects
				(font
					(size 1.27 1.27)
					(thickness 0.15)
				)
				(justify left bottom)
				(hide yes)
			)
		)
		(property "Voltage" ""
			(at 68.58 210.82 0)
			(effects
				(font
					(size 1.27 1.27)
				)
				(justify left bottom)
				(hide yes)
			)
		)
		(property "Dielectric" ""
			(at 66.04 210.82 0)
			(effects
				(font
					(size 1.27 1.27)
				)
				(justify left bottom)
				(hide yes)
			)
		)
		(pin "1"
		)
		(pin "2"
		)
		(instances
			(project "data-center-rdimm-ddr5-tester"
				(path ""
					(reference "C117")
					(unit 1)
				)
			)
		)
	)
	(symbol
		(lib_id "antmicropower:GND")
		(at 102.87 219.71 0)
		(unit 1)
		(exclude_from_sim no)
		(in_bom yes)
		(on_board yes)
		(dnp no)
		(fields_autoplaced yes)
		(property "Reference" "#PWR0231"
			(at 102.87 226.06 0)
			(effects
				(font
					(size 1.27 1.27)
				)
				(hide yes)
			)
		)
		(property "Value" "GND"
			(at 100.965 224.155 0)
			(effects
				(font
					(size 1.27 1.27)
					(thickness 0.15)
				)
				(justify left bottom)
			)
		)
		(property "Footprint" ""
			(at 111.76 227.33 0)
			(effects
				(font
					(size 1.27 1.27)
					(thickness 0.15)
				)
				(justify left bottom)
				(hide yes)
			)
		)
		(property "Datasheet" ""
			(at 111.76 232.41 0)
			(effects
				(font
					(size 1.27 1.27)
					(thickness 0.15)
				)
				(justify left bottom)
				(hide yes)
			)
		)
		(property "Description" ""
			(at 102.87 219.71 0)
			(effects
				(font
					(size 1.27 1.27)
				)
				(hide yes)
			)
		)
		(property "Author" "Antmicro"
			(at 111.76 224.79 0)
			(effects
				(font
					(size 1.27 1.27)
					(thickness 0.15)
				)
				(justify left bottom)
				(hide yes)
			)
		)
		(property "License" "Apache-2.0"
			(at 111.76 227.33 0)
			(effects
				(font
					(size 1.27 1.27)
					(thickness 0.15)
				)
				(justify left bottom)
				(hide yes)
			)
		)
		(pin "1"
		)
		(instances
			(project "data-center-rdimm-ddr5-tester"
				(path ""
					(reference "#PWR0231")
					(unit 1)
				)
			)
		)
	)
	(symbol
		(lib_id "antmicropower:GND")
		(at 96.52 195.58 0)
		(unit 1)
		(exclude_from_sim no)
		(in_bom yes)
		(on_board yes)
		(dnp no)
		(fields_autoplaced yes)
		(property "Reference" "#PWR0232"
			(at 96.52 201.93 0)
			(effects
				(font
					(size 1.27 1.27)
				)
				(hide yes)
			)
		)
		(property "Value" "GND"
			(at 94.615 200.025 0)
			(effects
				(font
					(size 1.27 1.27)
					(thickness 0.15)
				)
				(justify left bottom)
			)
		)
		(property "Footprint" ""
			(at 105.41 203.2 0)
			(effects
				(font
					(size 1.27 1.27)
					(thickness 0.15)
				)
				(justify left bottom)
				(hide yes)
			)
		)
		(property "Datasheet" ""
			(at 105.41 208.28 0)
			(effects
				(font
					(size 1.27 1.27)
					(thickness 0.15)
				)
				(justify left bottom)
				(hide yes)
			)
		)
		(property "Description" ""
			(at 96.52 195.58 0)
			(effects
				(font
					(size 1.27 1.27)
				)
				(hide yes)
			)
		)
		(property "Author" "Antmicro"
			(at 105.41 200.66 0)
			(effects
				(font
					(size 1.27 1.27)
					(thickness 0.15)
				)
				(justify left bottom)
				(hide yes)
			)
		)
		(property "License" "Apache-2.0"
			(at 105.41 203.2 0)
			(effects
				(font
					(size 1.27 1.27)
					(thickness 0.15)
				)
				(justify left bottom)
				(hide yes)
			)
		)
		(pin "1"
		)
		(instances
			(project "data-center-rdimm-ddr5-tester"
				(path ""
					(reference "#PWR0232")
					(unit 1)
				)
			)
		)
	)
	(symbol
		(lib_id "antmicropower:GND")
		(at 76.2 195.58 0)
		(unit 1)
		(exclude_from_sim no)
		(in_bom yes)
		(on_board yes)
		(dnp no)
		(fields_autoplaced yes)
		(property "Reference" "#PWR0235"
			(at 76.2 201.93 0)
			(effects
				(font
					(size 1.27 1.27)
				)
				(hide yes)
			)
		)
		(property "Value" "GND"
			(at 74.295 200.025 0)
			(effects
				(font
					(size 1.27 1.27)
					(thickness 0.15)
				)
				(justify left bottom)
			)
		)
		(property "Footprint" ""
			(at 85.09 203.2 0)
			(effects
				(font
					(size 1.27 1.27)
					(thickness 0.15)
				)
				(justify left bottom)
				(hide yes)
			)
		)
		(property "Datasheet" ""
			(at 85.09 208.28 0)
			(effects
				(font
					(size 1.27 1.27)
					(thickness 0.15)
				)
				(justify left bottom)
				(hide yes)
			)
		)
		(property "Description" ""
			(at 76.2 195.58 0)
			(effects
				(font
					(size 1.27 1.27)
				)
				(hide yes)
			)
		)
		(property "Author" "Antmicro"
			(at 85.09 200.66 0)
			(effects
				(font
					(size 1.27 1.27)
					(thickness 0.15)
				)
				(justify left bottom)
				(hide yes)
			)
		)
		(property "License" "Apache-2.0"
			(at 85.09 203.2 0)
			(effects
				(font
					(size 1.27 1.27)
					(thickness 0.15)
				)
				(justify left bottom)
				(hide yes)
			)
		)
		(pin "1"
		)
		(instances
			(project "data-center-rdimm-ddr5-tester"
				(path ""
					(reference "#PWR0235")
					(unit 1)
				)
			)
		)
	)
	(symbol
		(lib_id "antmicroCapacitors0402:C_100n_0402")
		(at 41.91 129.54 270)
		(unit 1)
		(exclude_from_sim no)
		(in_bom yes)
		(on_board yes)
		(dnp no)
		(property "Reference" "C115"
			(at 42.545 130.175 90)
			(effects
				(font
					(size 1.27 1.27)
				)
				(justify left)
			)
		)
		(property "Value" "C_100n_0402"
			(at 31.75 149.86 0)
			(effects
				(font
					(size 1.27 1.27)
					(thickness 0.15)
				)
				(justify left bottom)
				(hide yes)
			)
		)
		(property "Footprint" "antmicro-footprints:C_0402_1005Metric"
			(at 29.21 149.86 0)
			(effects
				(font
					(size 1.27 1.27)
					(thickness 0.15)
				)
				(justify left bottom)
				(hide yes)
			)
		)
		(property "Datasheet" "https://www.murata.com/products/productdetail?partno=GRM155R61H104KE14%23"
			(at 26.67 149.86 0)
			(effects
				(font
					(size 1.27 1.27)
					(thickness 0.15)
				)
				(justify left bottom)
				(hide yes)
			)
		)
		(property "Description" ""
			(at 41.91 129.54 0)
			(effects
				(font
					(size 1.27 1.27)
				)
				(hide yes)
			)
		)
		(property "Manufacturer" "Murata"
			(at 21.59 149.86 0)
			(effects
				(font
					(size 1.27 1.27)
					(thickness 0.15)
				)
				(justify left bottom)
				(hide yes)
			)
		)
		(property "MPN" "GRM155R61H104KE14D"
			(at 24.13 149.86 0)
			(effects
				(font
					(size 1.27 1.27)
					(thickness 0.15)
				)
				(justify left bottom)
				(hide yes)
			)
		)
		(property "Val" "100n"
			(at 42.545 133.985 90)
			(effects
				(font
					(size 1.27 1.27)
					(thickness 0.15)
				)
				(justify left)
			)
		)
		(property "License" "Apache-2.0"
			(at 19.05 149.86 0)
			(effects
				(font
					(size 1.27 1.27)
					(thickness 0.15)
				)
				(justify left bottom)
				(hide yes)
			)
		)
		(property "Author" "Antmicro"
			(at 16.51 149.86 0)
			(effects
				(font
					(size 1.27 1.27)
					(thickness 0.15)
				)
				(justify left bottom)
				(hide yes)
			)
		)
		(property "Voltage" "50V"
			(at 13.97 149.86 0)
			(effects
				(font
					(size 1.27 1.27)
				)
				(justify left bottom)
				(hide yes)
			)
		)
		(property "Dielectric" "X5R"
			(at 11.43 149.86 0)
			(effects
				(font
					(size 1.27 1.27)
				)
				(justify left bottom)
				(hide yes)
			)
		)
		(pin "1"
		)
		(pin "2"
		)
		(instances
			(project "data-center-rdimm-ddr5-tester"
				(path ""
					(reference "C115")
					(unit 1)
				)
			)
		)
	)
	(symbol
		(lib_id "antmicroCapacitors0402:C_100n_0402")
		(at 49.53 129.54 270)
		(unit 1)
		(exclude_from_sim no)
		(in_bom yes)
		(on_board yes)
		(dnp no)
		(property "Reference" "C118"
			(at 50.165 130.1751 90)
			(effects
				(font
					(size 1.27 1.27)
				)
				(justify left)
			)
		)
		(property "Value" "C_100n_0402"
			(at 39.37 149.86 0)
			(effects
				(font
					(size 1.27 1.27)
					(thickness 0.15)
				)
				(justify left bottom)
				(hide yes)
			)
		)
		(property "Footprint" "antmicro-footprints:C_0402_1005Metric"
			(at 36.83 149.86 0)
			(effects
				(font
					(size 1.27 1.27)
					(thickness 0.15)
				)
				(justify left bottom)
				(hide yes)
			)
		)
		(property "Datasheet" "https://www.murata.com/products/productdetail?partno=GRM155R61H104KE14%23"
			(at 34.29 149.86 0)
			(effects
				(font
					(size 1.27 1.27)
					(thickness 0.15)
				)
				(justify left bottom)
				(hide yes)
			)
		)
		(property "Description" ""
			(at 49.53 129.54 0)
			(effects
				(font
					(size 1.27 1.27)
				)
				(hide yes)
			)
		)
		(property "Manufacturer" "Murata"
			(at 29.21 149.86 0)
			(effects
				(font
					(size 1.27 1.27)
					(thickness 0.15)
				)
				(justify left bottom)
				(hide yes)
			)
		)
		(property "MPN" "GRM155R61H104KE14D"
			(at 31.75 149.86 0)
			(effects
				(font
					(size 1.27 1.27)
					(thickness 0.15)
				)
				(justify left bottom)
				(hide yes)
			)
		)
		(property "Val" "100n"
			(at 50.165 133.985 90)
			(effects
				(font
					(size 1.27 1.27)
					(thickness 0.15)
				)
				(justify left)
			)
		)
		(property "License" "Apache-2.0"
			(at 26.67 149.86 0)
			(effects
				(font
					(size 1.27 1.27)
					(thickness 0.15)
				)
				(justify left bottom)
				(hide yes)
			)
		)
		(property "Author" "Antmicro"
			(at 24.13 149.86 0)
			(effects
				(font
					(size 1.27 1.27)
					(thickness 0.15)
				)
				(justify left bottom)
				(hide yes)
			)
		)
		(property "Voltage" "50V"
			(at 21.59 149.86 0)
			(effects
				(font
					(size 1.27 1.27)
				)
				(justify left bottom)
				(hide yes)
			)
		)
		(property "Dielectric" "X5R"
			(at 19.05 149.86 0)
			(effects
				(font
					(size 1.27 1.27)
				)
				(justify left bottom)
				(hide yes)
			)
		)
		(pin "1"
		)
		(pin "2"
		)
		(instances
			(project "data-center-rdimm-ddr5-tester"
				(path ""
					(reference "C118")
					(unit 1)
				)
			)
		)
	)
	(symbol
		(lib_id "antmicroCapacitors0402:C_100n_0402")
		(at 57.15 129.54 270)
		(unit 1)
		(exclude_from_sim no)
		(in_bom yes)
		(on_board yes)
		(dnp no)
		(property "Reference" "C119"
			(at 57.785 130.1751 90)
			(effects
				(font
					(size 1.27 1.27)
				)
				(justify left)
			)
		)
		(property "Value" "C_100n_0402"
			(at 46.99 149.86 0)
			(effects
				(font
					(size 1.27 1.27)
					(thickness 0.15)
				)
				(justify left bottom)
				(hide yes)
			)
		)
		(property "Footprint" "antmicro-footprints:C_0402_1005Metric"
			(at 44.45 149.86 0)
			(effects
				(font
					(size 1.27 1.27)
					(thickness 0.15)
				)
				(justify left bottom)
				(hide yes)
			)
		)
		(property "Datasheet" "https://www.murata.com/products/productdetail?partno=GRM155R61H104KE14%23"
			(at 41.91 149.86 0)
			(effects
				(font
					(size 1.27 1.27)
					(thickness 0.15)
				)
				(justify left bottom)
				(hide yes)
			)
		)
		(property "Description" ""
			(at 57.15 129.54 0)
			(effects
				(font
					(size 1.27 1.27)
				)
				(hide yes)
			)
		)
		(property "Manufacturer" "Murata"
			(at 36.83 149.86 0)
			(effects
				(font
					(size 1.27 1.27)
					(thickness 0.15)
				)
				(justify left bottom)
				(hide yes)
			)
		)
		(property "MPN" "GRM155R61H104KE14D"
			(at 39.37 149.86 0)
			(effects
				(font
					(size 1.27 1.27)
					(thickness 0.15)
				)
				(justify left bottom)
				(hide yes)
			)
		)
		(property "Val" "100n"
			(at 57.785 133.985 90)
			(effects
				(font
					(size 1.27 1.27)
					(thickness 0.15)
				)
				(justify left)
			)
		)
		(property "License" "Apache-2.0"
			(at 34.29 149.86 0)
			(effects
				(font
					(size 1.27 1.27)
					(thickness 0.15)
				)
				(justify left bottom)
				(hide yes)
			)
		)
		(property "Author" "Antmicro"
			(at 31.75 149.86 0)
			(effects
				(font
					(size 1.27 1.27)
					(thickness 0.15)
				)
				(justify left bottom)
				(hide yes)
			)
		)
		(property "Voltage" "50V"
			(at 29.21 149.86 0)
			(effects
				(font
					(size 1.27 1.27)
				)
				(justify left bottom)
				(hide yes)
			)
		)
		(property "Dielectric" "X5R"
			(at 26.67 149.86 0)
			(effects
				(font
					(size 1.27 1.27)
				)
				(justify left bottom)
				(hide yes)
			)
		)
		(pin "1"
		)
		(pin "2"
		)
		(instances
			(project "data-center-rdimm-ddr5-tester"
				(path ""
					(reference "C119")
					(unit 1)
				)
			)
		)
	)
	(symbol
		(lib_id "antmicroCapacitors0402:C_100n_0402")
		(at 64.77 129.54 270)
		(unit 1)
		(exclude_from_sim no)
		(in_bom yes)
		(on_board yes)
		(dnp no)
		(property "Reference" "C120"
			(at 65.405 130.1751 90)
			(effects
				(font
					(size 1.27 1.27)
				)
				(justify left)
			)
		)
		(property "Value" "C_100n_0402"
			(at 54.61 149.86 0)
			(effects
				(font
					(size 1.27 1.27)
					(thickness 0.15)
				)
				(justify left bottom)
				(hide yes)
			)
		)
		(property "Footprint" "antmicro-footprints:C_0402_1005Metric"
			(at 52.07 149.86 0)
			(effects
				(font
					(size 1.27 1.27)
					(thickness 0.15)
				)
				(justify left bottom)
				(hide yes)
			)
		)
		(property "Datasheet" "https://www.murata.com/products/productdetail?partno=GRM155R61H104KE14%23"
			(at 49.53 149.86 0)
			(effects
				(font
					(size 1.27 1.27)
					(thickness 0.15)
				)
				(justify left bottom)
				(hide yes)
			)
		)
		(property "Description" ""
			(at 64.77 129.54 0)
			(effects
				(font
					(size 1.27 1.27)
				)
				(hide yes)
			)
		)
		(property "Manufacturer" "Murata"
			(at 44.45 149.86 0)
			(effects
				(font
					(size 1.27 1.27)
					(thickness 0.15)
				)
				(justify left bottom)
				(hide yes)
			)
		)
		(property "MPN" "GRM155R61H104KE14D"
			(at 46.99 149.86 0)
			(effects
				(font
					(size 1.27 1.27)
					(thickness 0.15)
				)
				(justify left bottom)
				(hide yes)
			)
		)
		(property "Val" "100n"
			(at 65.405 133.985 90)
			(effects
				(font
					(size 1.27 1.27)
					(thickness 0.15)
				)
				(justify left)
			)
		)
		(property "License" "Apache-2.0"
			(at 41.91 149.86 0)
			(effects
				(font
					(size 1.27 1.27)
					(thickness 0.15)
				)
				(justify left bottom)
				(hide yes)
			)
		)
		(property "Author" "Antmicro"
			(at 39.37 149.86 0)
			(effects
				(font
					(size 1.27 1.27)
					(thickness 0.15)
				)
				(justify left bottom)
				(hide yes)
			)
		)
		(property "Voltage" "50V"
			(at 36.83 149.86 0)
			(effects
				(font
					(size 1.27 1.27)
				)
				(justify left bottom)
				(hide yes)
			)
		)
		(property "Dielectric" "X5R"
			(at 34.29 149.86 0)
			(effects
				(font
					(size 1.27 1.27)
				)
				(justify left bottom)
				(hide yes)
			)
		)
		(pin "1"
		)
		(pin "2"
		)
		(instances
			(project "data-center-rdimm-ddr5-tester"
				(path ""
					(reference "C120")
					(unit 1)
				)
			)
		)
	)
	(symbol
		(lib_id "antmicropower:GND")
		(at 41.91 134.62 0)
		(unit 1)
		(exclude_from_sim no)
		(in_bom yes)
		(on_board yes)
		(dnp no)
		(fields_autoplaced yes)
		(property "Reference" "#PWR0347"
			(at 41.91 140.97 0)
			(effects
				(font
					(size 1.27 1.27)
				)
				(hide yes)
			)
		)
		(property "Value" "GND"
			(at 40.005 139.065 0)
			(effects
				(font
					(size 1.27 1.27)
					(thickness 0.15)
				)
				(justify left bottom)
			)
		)
		(property "Footprint" ""
			(at 50.8 142.24 0)
			(effects
				(font
					(size 1.27 1.27)
					(thickness 0.15)
				)
				(justify left bottom)
				(hide yes)
			)
		)
		(property "Datasheet" ""
			(at 50.8 147.32 0)
			(effects
				(font
					(size 1.27 1.27)
					(thickness 0.15)
				)
				(justify left bottom)
				(hide yes)
			)
		)
		(property "Description" ""
			(at 41.91 134.62 0)
			(effects
				(font
					(size 1.27 1.27)
				)
				(hide yes)
			)
		)
		(property "Author" "Antmicro"
			(at 50.8 139.7 0)
			(effects
				(font
					(size 1.27 1.27)
					(thickness 0.15)
				)
				(justify left bottom)
				(hide yes)
			)
		)
		(property "License" "Apache-2.0"
			(at 50.8 142.24 0)
			(effects
				(font
					(size 1.27 1.27)
					(thickness 0.15)
				)
				(justify left bottom)
				(hide yes)
			)
		)
		(pin "1"
		)
		(instances
			(project "data-center-rdimm-ddr5-tester"
				(path ""
					(reference "#PWR0347")
					(unit 1)
				)
			)
		)
	)
	(symbol
		(lib_id "antmicropower:GND")
		(at 49.53 134.62 0)
		(unit 1)
		(exclude_from_sim no)
		(in_bom yes)
		(on_board yes)
		(dnp no)
		(fields_autoplaced yes)
		(property "Reference" "#PWR0348"
			(at 49.53 140.97 0)
			(effects
				(font
					(size 1.27 1.27)
				)
				(hide yes)
			)
		)
		(property "Value" "GND"
			(at 47.625 139.065 0)
			(effects
				(font
					(size 1.27 1.27)
					(thickness 0.15)
				)
				(justify left bottom)
			)
		)
		(property "Footprint" ""
			(at 58.42 142.24 0)
			(effects
				(font
					(size 1.27 1.27)
					(thickness 0.15)
				)
				(justify left bottom)
				(hide yes)
			)
		)
		(property "Datasheet" ""
			(at 58.42 147.32 0)
			(effects
				(font
					(size 1.27 1.27)
					(thickness 0.15)
				)
				(justify left bottom)
				(hide yes)
			)
		)
		(property "Description" ""
			(at 49.53 134.62 0)
			(effects
				(font
					(size 1.27 1.27)
				)
				(hide yes)
			)
		)
		(property "Author" "Antmicro"
			(at 58.42 139.7 0)
			(effects
				(font
					(size 1.27 1.27)
					(thickness 0.15)
				)
				(justify left bottom)
				(hide yes)
			)
		)
		(property "License" "Apache-2.0"
			(at 58.42 142.24 0)
			(effects
				(font
					(size 1.27 1.27)
					(thickness 0.15)
				)
				(justify left bottom)
				(hide yes)
			)
		)
		(pin "1"
		)
		(instances
			(project "data-center-rdimm-ddr5-tester"
				(path ""
					(reference "#PWR0348")
					(unit 1)
				)
			)
		)
	)
	(symbol
		(lib_id "antmicropower:GND")
		(at 57.15 134.62 0)
		(unit 1)
		(exclude_from_sim no)
		(in_bom yes)
		(on_board yes)
		(dnp no)
		(fields_autoplaced yes)
		(property "Reference" "#PWR0260"
			(at 57.15 140.97 0)
			(effects
				(font
					(size 1.27 1.27)
				)
				(hide yes)
			)
		)
		(property "Value" "GND"
			(at 55.245 139.065 0)
			(effects
				(font
					(size 1.27 1.27)
					(thickness 0.15)
				)
				(justify left bottom)
			)
		)
		(property "Footprint" ""
			(at 66.04 142.24 0)
			(effects
				(font
					(size 1.27 1.27)
					(thickness 0.15)
				)
				(justify left bottom)
				(hide yes)
			)
		)
		(property "Datasheet" ""
			(at 66.04 147.32 0)
			(effects
				(font
					(size 1.27 1.27)
					(thickness 0.15)
				)
				(justify left bottom)
				(hide yes)
			)
		)
		(property "Description" ""
			(at 57.15 134.62 0)
			(effects
				(font
					(size 1.27 1.27)
				)
				(hide yes)
			)
		)
		(property "Author" "Antmicro"
			(at 66.04 139.7 0)
			(effects
				(font
					(size 1.27 1.27)
					(thickness 0.15)
				)
				(justify left bottom)
				(hide yes)
			)
		)
		(property "License" "Apache-2.0"
			(at 66.04 142.24 0)
			(effects
				(font
					(size 1.27 1.27)
					(thickness 0.15)
				)
				(justify left bottom)
				(hide yes)
			)
		)
		(pin "1"
		)
		(instances
			(project "data-center-rdimm-ddr5-tester"
				(path ""
					(reference "#PWR0260")
					(unit 1)
				)
			)
		)
	)
	(symbol
		(lib_id "antmicropower:GND")
		(at 64.77 134.62 0)
		(unit 1)
		(exclude_from_sim no)
		(in_bom yes)
		(on_board yes)
		(dnp no)
		(fields_autoplaced yes)
		(property "Reference" "#PWR0334"
			(at 64.77 140.97 0)
			(effects
				(font
					(size 1.27 1.27)
				)
				(hide yes)
			)
		)
		(property "Value" "GND"
			(at 62.865 139.065 0)
			(effects
				(font
					(size 1.27 1.27)
					(thickness 0.15)
				)
				(justify left bottom)
			)
		)
		(property "Footprint" ""
			(at 73.66 142.24 0)
			(effects
				(font
					(size 1.27 1.27)
					(thickness 0.15)
				)
				(justify left bottom)
				(hide yes)
			)
		)
		(property "Datasheet" ""
			(at 73.66 147.32 0)
			(effects
				(font
					(size 1.27 1.27)
					(thickness 0.15)
				)
				(justify left bottom)
				(hide yes)
			)
		)
		(property "Description" ""
			(at 64.77 134.62 0)
			(effects
				(font
					(size 1.27 1.27)
				)
				(hide yes)
			)
		)
		(property "Author" "Antmicro"
			(at 73.66 139.7 0)
			(effects
				(font
					(size 1.27 1.27)
					(thickness 0.15)
				)
				(justify left bottom)
				(hide yes)
			)
		)
		(property "License" "Apache-2.0"
			(at 73.66 142.24 0)
			(effects
				(font
					(size 1.27 1.27)
					(thickness 0.15)
				)
				(justify left bottom)
				(hide yes)
			)
		)
		(pin "1"
		)
		(instances
			(project "data-center-rdimm-ddr5-tester"
				(path ""
					(reference "#PWR0334")
					(unit 1)
				)
			)
		)
	)
	(symbol
		(lib_id "antmicroCapacitors0402:C_100n_0402")
		(at 53.34 186.69 270)
		(unit 1)
		(exclude_from_sim no)
		(in_bom yes)
		(on_board yes)
		(dnp no)
		(property "Reference" "C123"
			(at 53.975 187.325 90)
			(effects
				(font
					(size 1.27 1.27)
				)
				(justify left)
			)
		)
		(property "Value" "C_100n_0402"
			(at 43.18 207.01 0)
			(effects
				(font
					(size 1.27 1.27)
					(thickness 0.15)
				)
				(justify left bottom)
				(hide yes)
			)
		)
		(property "Footprint" "antmicro-footprints:C_0402_1005Metric"
			(at 40.64 207.01 0)
			(effects
				(font
					(size 1.27 1.27)
					(thickness 0.15)
				)
				(justify left bottom)
				(hide yes)
			)
		)
		(property "Datasheet" "https://www.murata.com/products/productdetail?partno=GRM155R61H104KE14%23"
			(at 38.1 207.01 0)
			(effects
				(font
					(size 1.27 1.27)
					(thickness 0.15)
				)
				(justify left bottom)
				(hide yes)
			)
		)
		(property "Description" ""
			(at 53.34 186.69 0)
			(effects
				(font
					(size 1.27 1.27)
				)
				(hide yes)
			)
		)
		(property "Manufacturer" "Murata"
			(at 33.02 207.01 0)
			(effects
				(font
					(size 1.27 1.27)
					(thickness 0.15)
				)
				(justify left bottom)
				(hide yes)
			)
		)
		(property "MPN" "GRM155R61H104KE14D"
			(at 35.56 207.01 0)
			(effects
				(font
					(size 1.27 1.27)
					(thickness 0.15)
				)
				(justify left bottom)
				(hide yes)
			)
		)
		(property "Val" "100n"
			(at 53.975 191.135 90)
			(effects
				(font
					(size 1.27 1.27)
					(thickness 0.15)
				)
				(justify left)
			)
		)
		(property "License" "Apache-2.0"
			(at 30.48 207.01 0)
			(effects
				(font
					(size 1.27 1.27)
					(thickness 0.15)
				)
				(justify left bottom)
				(hide yes)
			)
		)
		(property "Author" "Antmicro"
			(at 27.94 207.01 0)
			(effects
				(font
					(size 1.27 1.27)
					(thickness 0.15)
				)
				(justify left bottom)
				(hide yes)
			)
		)
		(property "Voltage" "50V"
			(at 25.4 207.01 0)
			(effects
				(font
					(size 1.27 1.27)
				)
				(justify left bottom)
				(hide yes)
			)
		)
		(property "Dielectric" "X5R"
			(at 22.86 207.01 0)
			(effects
				(font
					(size 1.27 1.27)
				)
				(justify left bottom)
				(hide yes)
			)
		)
		(pin "1"
		)
		(pin "2"
		)
		(instances
			(project "data-center-rdimm-ddr5-tester"
				(path ""
					(reference "C123")
					(unit 1)
				)
			)
		)
	)
	(symbol
		(lib_id "antmicroCapacitors0402:C_100n_0402")
		(at 60.96 186.69 270)
		(unit 1)
		(exclude_from_sim no)
		(in_bom yes)
		(on_board yes)
		(dnp no)
		(property "Reference" "C125"
			(at 61.595 187.325 90)
			(effects
				(font
					(size 1.27 1.27)
				)
				(justify left)
			)
		)
		(property "Value" "C_100n_0402"
			(at 50.8 207.01 0)
			(effects
				(font
					(size 1.27 1.27)
					(thickness 0.15)
				)
				(justify left bottom)
				(hide yes)
			)
		)
		(property "Footprint" "antmicro-footprints:C_0402_1005Metric"
			(at 48.26 207.01 0)
			(effects
				(font
					(size 1.27 1.27)
					(thickness 0.15)
				)
				(justify left bottom)
				(hide yes)
			)
		)
		(property "Datasheet" "https://www.murata.com/products/productdetail?partno=GRM155R61H104KE14%23"
			(at 45.72 207.01 0)
			(effects
				(font
					(size 1.27 1.27)
					(thickness 0.15)
				)
				(justify left bottom)
				(hide yes)
			)
		)
		(property "Description" ""
			(at 60.96 186.69 0)
			(effects
				(font
					(size 1.27 1.27)
				)
				(hide yes)
			)
		)
		(property "Manufacturer" "Murata"
			(at 40.64 207.01 0)
			(effects
				(font
					(size 1.27 1.27)
					(thickness 0.15)
				)
				(justify left bottom)
				(hide yes)
			)
		)
		(property "MPN" "GRM155R61H104KE14D"
			(at 43.18 207.01 0)
			(effects
				(font
					(size 1.27 1.27)
					(thickness 0.15)
				)
				(justify left bottom)
				(hide yes)
			)
		)
		(property "Val" "100n"
			(at 61.595 191.135 90)
			(effects
				(font
					(size 1.27 1.27)
					(thickness 0.15)
				)
				(justify left)
			)
		)
		(property "License" "Apache-2.0"
			(at 38.1 207.01 0)
			(effects
				(font
					(size 1.27 1.27)
					(thickness 0.15)
				)
				(justify left bottom)
				(hide yes)
			)
		)
		(property "Author" "Antmicro"
			(at 35.56 207.01 0)
			(effects
				(font
					(size 1.27 1.27)
					(thickness 0.15)
				)
				(justify left bottom)
				(hide yes)
			)
		)
		(property "Voltage" "50V"
			(at 33.02 207.01 0)
			(effects
				(font
					(size 1.27 1.27)
				)
				(justify left bottom)
				(hide yes)
			)
		)
		(property "Dielectric" "X5R"
			(at 30.48 207.01 0)
			(effects
				(font
					(size 1.27 1.27)
				)
				(justify left bottom)
				(hide yes)
			)
		)
		(pin "1"
		)
		(pin "2"
		)
		(instances
			(project "data-center-rdimm-ddr5-tester"
				(path ""
					(reference "C125")
					(unit 1)
				)
			)
		)
	)
	(symbol
		(lib_id "antmicropower:GND")
		(at 53.34 191.77 0)
		(unit 1)
		(exclude_from_sim no)
		(in_bom yes)
		(on_board yes)
		(dnp no)
		(fields_autoplaced yes)
		(property "Reference" "#PWR0239"
			(at 53.34 198.12 0)
			(effects
				(font
					(size 1.27 1.27)
				)
				(hide yes)
			)
		)
		(property "Value" "GND"
			(at 51.435 196.215 0)
			(effects
				(font
					(size 1.27 1.27)
					(thickness 0.15)
				)
				(justify left bottom)
			)
		)
		(property "Footprint" ""
			(at 62.23 199.39 0)
			(effects
				(font
					(size 1.27 1.27)
					(thickness 0.15)
				)
				(justify left bottom)
				(hide yes)
			)
		)
		(property "Datasheet" ""
			(at 62.23 204.47 0)
			(effects
				(font
					(size 1.27 1.27)
					(thickness 0.15)
				)
				(justify left bottom)
				(hide yes)
			)
		)
		(property "Description" ""
			(at 53.34 191.77 0)
			(effects
				(font
					(size 1.27 1.27)
				)
				(hide yes)
			)
		)
		(property "Author" "Antmicro"
			(at 62.23 196.85 0)
			(effects
				(font
					(size 1.27 1.27)
					(thickness 0.15)
				)
				(justify left bottom)
				(hide yes)
			)
		)
		(property "License" "Apache-2.0"
			(at 62.23 199.39 0)
			(effects
				(font
					(size 1.27 1.27)
					(thickness 0.15)
				)
				(justify left bottom)
				(hide yes)
			)
		)
		(pin "1"
		)
		(instances
			(project "data-center-rdimm-ddr5-tester"
				(path ""
					(reference "#PWR0239")
					(unit 1)
				)
			)
		)
	)
	(symbol
		(lib_id "antmicropower:GND")
		(at 60.96 191.77 0)
		(unit 1)
		(exclude_from_sim no)
		(in_bom yes)
		(on_board yes)
		(dnp no)
		(fields_autoplaced yes)
		(property "Reference" "#PWR0246"
			(at 60.96 198.12 0)
			(effects
				(font
					(size 1.27 1.27)
				)
				(hide yes)
			)
		)
		(property "Value" "GND"
			(at 59.055 196.215 0)
			(effects
				(font
					(size 1.27 1.27)
					(thickness 0.15)
				)
				(justify left bottom)
			)
		)
		(property "Footprint" ""
			(at 69.85 199.39 0)
			(effects
				(font
					(size 1.27 1.27)
					(thickness 0.15)
				)
				(justify left bottom)
				(hide yes)
			)
		)
		(property "Datasheet" ""
			(at 69.85 204.47 0)
			(effects
				(font
					(size 1.27 1.27)
					(thickness 0.15)
				)
				(justify left bottom)
				(hide yes)
			)
		)
		(property "Description" ""
			(at 60.96 191.77 0)
			(effects
				(font
					(size 1.27 1.27)
				)
				(hide yes)
			)
		)
		(property "Author" "Antmicro"
			(at 69.85 196.85 0)
			(effects
				(font
					(size 1.27 1.27)
					(thickness 0.15)
				)
				(justify left bottom)
				(hide yes)
			)
		)
		(property "License" "Apache-2.0"
			(at 69.85 199.39 0)
			(effects
				(font
					(size 1.27 1.27)
					(thickness 0.15)
				)
				(justify left bottom)
				(hide yes)
			)
		)
		(pin "1"
		)
		(instances
			(project "data-center-rdimm-ddr5-tester"
				(path ""
					(reference "#PWR0246")
					(unit 1)
				)
			)
		)
	)
	(symbol
		(lib_id "antmicroCapacitors0402:C_4u7_0402")
		(at 45.72 186.69 270)
		(unit 1)
		(exclude_from_sim no)
		(in_bom yes)
		(on_board yes)
		(dnp no)
		(property "Reference" "C122"
			(at 46.355 187.325 90)
			(effects
				(font
					(size 1.27 1.27)
				)
				(justify left)
			)
		)
		(property "Value" "C_4u7_0402"
			(at 35.56 207.01 0)
			(effects
				(font
					(size 1.27 1.27)
					(thickness 0.15)
				)
				(justify left bottom)
				(hide yes)
			)
		)
		(property "Footprint" "antmicro-footprints:C_0402_1005Metric"
			(at 33.02 207.01 0)
			(effects
				(font
					(size 1.27 1.27)
					(thickness 0.15)
				)
				(justify left bottom)
				(hide yes)
			)
		)
		(property "Datasheet" "https://www.murata.com/products/productdetail?partno=GRM155R61A475MEAA%23"
			(at 30.48 207.01 0)
			(effects
				(font
					(size 1.27 1.27)
					(thickness 0.15)
				)
				(justify left bottom)
				(hide yes)
			)
		)
		(property "Description" ""
			(at 45.72 186.69 0)
			(effects
				(font
					(size 1.27 1.27)
				)
				(hide yes)
			)
		)
		(property "Manufacturer" "Murata"
			(at 25.4 207.01 0)
			(effects
				(font
					(size 1.27 1.27)
					(thickness 0.15)
				)
				(justify left bottom)
				(hide yes)
			)
		)
		(property "MPN" "GRM155R61A475MEAAD"
			(at 27.94 207.01 0)
			(effects
				(font
					(size 1.27 1.27)
					(thickness 0.15)
				)
				(justify left bottom)
				(hide yes)
			)
		)
		(property "Val" "4u7"
			(at 46.355 191.135 90)
			(effects
				(font
					(size 1.27 1.27)
					(thickness 0.15)
				)
				(justify left)
			)
		)
		(property "License" "Apache-2.0"
			(at 22.86 207.01 0)
			(effects
				(font
					(size 1.27 1.27)
					(thickness 0.15)
				)
				(justify left bottom)
				(hide yes)
			)
		)
		(property "Author" "Antmicro"
			(at 20.32 207.01 0)
			(effects
				(font
					(size 1.27 1.27)
					(thickness 0.15)
				)
				(justify left bottom)
				(hide yes)
			)
		)
		(property "Voltage" ""
			(at 17.78 207.01 0)
			(effects
				(font
					(size 1.27 1.27)
				)
				(justify left bottom)
				(hide yes)
			)
		)
		(property "Dielectric" ""
			(at 15.24 207.01 0)
			(effects
				(font
					(size 1.27 1.27)
				)
				(justify left bottom)
				(hide yes)
			)
		)
		(pin "1"
		)
		(pin "2"
		)
		(instances
			(project "data-center-rdimm-ddr5-tester"
				(path ""
					(reference "C122")
					(unit 1)
				)
			)
		)
	)
	(symbol
		(lib_id "antmicropower:GND")
		(at 45.72 191.77 0)
		(unit 1)
		(exclude_from_sim no)
		(in_bom yes)
		(on_board yes)
		(dnp no)
		(fields_autoplaced yes)
		(property "Reference" "#PWR0229"
			(at 45.72 198.12 0)
			(effects
				(font
					(size 1.27 1.27)
				)
				(hide yes)
			)
		)
		(property "Value" "GND"
			(at 43.815 196.215 0)
			(effects
				(font
					(size 1.27 1.27)
					(thickness 0.15)
				)
				(justify left bottom)
			)
		)
		(property "Footprint" ""
			(at 54.61 199.39 0)
			(effects
				(font
					(size 1.27 1.27)
					(thickness 0.15)
				)
				(justify left bottom)
				(hide yes)
			)
		)
		(property "Datasheet" ""
			(at 54.61 204.47 0)
			(effects
				(font
					(size 1.27 1.27)
					(thickness 0.15)
				)
				(justify left bottom)
				(hide yes)
			)
		)
		(property "Description" ""
			(at 45.72 191.77 0)
			(effects
				(font
					(size 1.27 1.27)
				)
				(hide yes)
			)
		)
		(property "Author" "Antmicro"
			(at 54.61 196.85 0)
			(effects
				(font
					(size 1.27 1.27)
					(thickness 0.15)
				)
				(justify left bottom)
				(hide yes)
			)
		)
		(property "License" "Apache-2.0"
			(at 54.61 199.39 0)
			(effects
				(font
					(size 1.27 1.27)
					(thickness 0.15)
				)
				(justify left bottom)
				(hide yes)
			)
		)
		(pin "1"
		)
		(instances
			(project "data-center-rdimm-ddr5-tester"
				(path ""
					(reference "#PWR0229")
					(unit 1)
				)
			)
		)
	)
	(symbol
		(lib_id "antmicroResistors0402:R_22R_0402")
		(at 284.48 138.43 0)
		(unit 1)
		(exclude_from_sim no)
		(in_bom yes)
		(on_board yes)
		(dnp no)
		(property "Reference" "R47"
			(at 282.575 137.16 0)
			(effects
				(font
					(size 1.27 1.27)
				)
			)
		)
		(property "Value" "R_22R_0402"
			(at 304.8 151.13 0)
			(effects
				(font
					(size 1.27 1.27)
					(thickness 0.15)
				)
				(justify left bottom)
				(hide yes)
			)
		)
		(property "Footprint" "antmicro-footprints:R_0402_1005Metric"
			(at 304.8 153.67 0)
			(effects
				(font
					(size 1.27 1.27)
					(thickness 0.15)
				)
				(justify left bottom)
				(hide yes)
			)
		)
		(property "Datasheet" "https://www.bourns.com/docs/product-datasheets/cr.pdf"
			(at 304.8 156.21 0)
			(effects
				(font
					(size 1.27 1.27)
					(thickness 0.15)
				)
				(justify left bottom)
				(hide yes)
			)
		)
		(property "Description" ""
			(at 284.48 138.43 0)
			(effects
				(font
					(size 1.27 1.27)
				)
				(hide yes)
			)
		)
		(property "Manufacturer" "Bourns"
			(at 304.8 161.29 0)
			(effects
				(font
					(size 1.27 1.27)
					(thickness 0.15)
				)
				(justify left bottom)
				(hide yes)
			)
		)
		(property "MPN" "CR0402-FX-22R0GLF"
			(at 304.8 158.75 0)
			(effects
				(font
					(size 1.27 1.27)
					(thickness 0.15)
				)
				(justify left bottom)
				(hide yes)
			)
		)
		(property "Val" "22R"
			(at 291.465 137.16 0)
			(effects
				(font
					(size 1.27 1.27)
					(thickness 0.15)
				)
			)
		)
		(property "License" "Apache-2.0"
			(at 304.8 163.83 0)
			(effects
				(font
					(size 1.27 1.27)
					(thickness 0.15)
				)
				(justify left bottom)
				(hide yes)
			)
		)
		(property "Author" "Antmicro"
			(at 304.8 166.37 0)
			(effects
				(font
					(size 1.27 1.27)
					(thickness 0.15)
				)
				(justify left bottom)
				(hide yes)
			)
		)
		(property "Tolerance" "1%"
			(at 304.8 148.59 0)
			(effects
				(font
					(size 1.27 1.27)
				)
				(justify left bottom)
				(hide yes)
			)
		)
		(pin "1"
		)
		(pin "2"
		)
		(instances
			(project "data-center-rdimm-ddr5-tester"
				(path ""
					(reference "R47")
					(unit 1)
				)
			)
		)
	)
	(symbol
		(lib_id "antmicroResistors0402:R_22R_0402")
		(at 284.48 143.51 0)
		(unit 1)
		(exclude_from_sim no)
		(in_bom yes)
		(on_board yes)
		(dnp no)
		(property "Reference" "R49"
			(at 282.575 142.24 0)
			(effects
				(font
					(size 1.27 1.27)
				)
			)
		)
		(property "Value" "R_22R_0402"
			(at 304.8 156.21 0)
			(effects
				(font
					(size 1.27 1.27)
					(thickness 0.15)
				)
				(justify left bottom)
				(hide yes)
			)
		)
		(property "Footprint" "antmicro-footprints:R_0402_1005Metric"
			(at 304.8 158.75 0)
			(effects
				(font
					(size 1.27 1.27)
					(thickness 0.15)
				)
				(justify left bottom)
				(hide yes)
			)
		)
		(property "Datasheet" "https://www.bourns.com/docs/product-datasheets/cr.pdf"
			(at 304.8 161.29 0)
			(effects
				(font
					(size 1.27 1.27)
					(thickness 0.15)
				)
				(justify left bottom)
				(hide yes)
			)
		)
		(property "Description" ""
			(at 284.48 143.51 0)
			(effects
				(font
					(size 1.27 1.27)
				)
				(hide yes)
			)
		)
		(property "Manufacturer" "Bourns"
			(at 304.8 166.37 0)
			(effects
				(font
					(size 1.27 1.27)
					(thickness 0.15)
				)
				(justify left bottom)
				(hide yes)
			)
		)
		(property "MPN" "CR0402-FX-22R0GLF"
			(at 304.8 163.83 0)
			(effects
				(font
					(size 1.27 1.27)
					(thickness 0.15)
				)
				(justify left bottom)
				(hide yes)
			)
		)
		(property "Val" "22R"
			(at 291.465 142.24 0)
			(effects
				(font
					(size 1.27 1.27)
					(thickness 0.15)
				)
			)
		)
		(property "License" "Apache-2.0"
			(at 304.8 168.91 0)
			(effects
				(font
					(size 1.27 1.27)
					(thickness 0.15)
				)
				(justify left bottom)
				(hide yes)
			)
		)
		(property "Author" "Antmicro"
			(at 304.8 171.45 0)
			(effects
				(font
					(size 1.27 1.27)
					(thickness 0.15)
				)
				(justify left bottom)
				(hide yes)
			)
		)
		(property "Tolerance" "1%"
			(at 304.8 153.67 0)
			(effects
				(font
					(size 1.27 1.27)
				)
				(justify left bottom)
				(hide yes)
			)
		)
		(pin "1"
		)
		(pin "2"
		)
		(instances
			(project "data-center-rdimm-ddr5-tester"
				(path ""
					(reference "R49")
					(unit 1)
				)
			)
		)
	)
	(symbol
		(lib_id "antmicroResistors0402:R_22R_0402")
		(at 284.48 146.05 0)
		(unit 1)
		(exclude_from_sim no)
		(in_bom yes)
		(on_board yes)
		(dnp no)
		(property "Reference" "R50"
			(at 282.575 144.78 0)
			(effects
				(font
					(size 1.27 1.27)
				)
			)
		)
		(property "Value" "R_22R_0402"
			(at 304.8 158.75 0)
			(effects
				(font
					(size 1.27 1.27)
					(thickness 0.15)
				)
				(justify left bottom)
				(hide yes)
			)
		)
		(property "Footprint" "antmicro-footprints:R_0402_1005Metric"
			(at 304.8 161.29 0)
			(effects
				(font
					(size 1.27 1.27)
					(thickness 0.15)
				)
				(justify left bottom)
				(hide yes)
			)
		)
		(property "Datasheet" "https://www.bourns.com/docs/product-datasheets/cr.pdf"
			(at 304.8 163.83 0)
			(effects
				(font
					(size 1.27 1.27)
					(thickness 0.15)
				)
				(justify left bottom)
				(hide yes)
			)
		)
		(property "Description" ""
			(at 284.48 146.05 0)
			(effects
				(font
					(size 1.27 1.27)
				)
				(hide yes)
			)
		)
		(property "Manufacturer" "Bourns"
			(at 304.8 168.91 0)
			(effects
				(font
					(size 1.27 1.27)
					(thickness 0.15)
				)
				(justify left bottom)
				(hide yes)
			)
		)
		(property "MPN" "CR0402-FX-22R0GLF"
			(at 304.8 166.37 0)
			(effects
				(font
					(size 1.27 1.27)
					(thickness 0.15)
				)
				(justify left bottom)
				(hide yes)
			)
		)
		(property "Val" "22R"
			(at 291.465 144.78 0)
			(effects
				(font
					(size 1.27 1.27)
					(thickness 0.15)
				)
			)
		)
		(property "License" "Apache-2.0"
			(at 304.8 171.45 0)
			(effects
				(font
					(size 1.27 1.27)
					(thickness 0.15)
				)
				(justify left bottom)
				(hide yes)
			)
		)
		(property "Author" "Antmicro"
			(at 304.8 173.99 0)
			(effects
				(font
					(size 1.27 1.27)
					(thickness 0.15)
				)
				(justify left bottom)
				(hide yes)
			)
		)
		(property "Tolerance" "1%"
			(at 304.8 156.21 0)
			(effects
				(font
					(size 1.27 1.27)
				)
				(justify left bottom)
				(hide yes)
			)
		)
		(pin "1"
		)
		(pin "2"
		)
		(instances
			(project "data-center-rdimm-ddr5-tester"
				(path ""
					(reference "R50")
					(unit 1)
				)
			)
		)
	)
	(symbol
		(lib_id "antmicroResistors0402:R_22R_0402")
		(at 284.48 140.97 0)
		(unit 1)
		(exclude_from_sim no)
		(in_bom yes)
		(on_board yes)
		(dnp no)
		(property "Reference" "R48"
			(at 282.575 139.7 0)
			(effects
				(font
					(size 1.27 1.27)
				)
			)
		)
		(property "Value" "R_22R_0402"
			(at 304.8 153.67 0)
			(effects
				(font
					(size 1.27 1.27)
					(thickness 0.15)
				)
				(justify left bottom)
				(hide yes)
			)
		)
		(property "Footprint" "antmicro-footprints:R_0402_1005Metric"
			(at 304.8 156.21 0)
			(effects
				(font
					(size 1.27 1.27)
					(thickness 0.15)
				)
				(justify left bottom)
				(hide yes)
			)
		)
		(property "Datasheet" "https://www.bourns.com/docs/product-datasheets/cr.pdf"
			(at 304.8 158.75 0)
			(effects
				(font
					(size 1.27 1.27)
					(thickness 0.15)
				)
				(justify left bottom)
				(hide yes)
			)
		)
		(property "Description" ""
			(at 284.48 140.97 0)
			(effects
				(font
					(size 1.27 1.27)
				)
				(hide yes)
			)
		)
		(property "Manufacturer" "Bourns"
			(at 304.8 163.83 0)
			(effects
				(font
					(size 1.27 1.27)
					(thickness 0.15)
				)
				(justify left bottom)
				(hide yes)
			)
		)
		(property "MPN" "CR0402-FX-22R0GLF"
			(at 304.8 161.29 0)
			(effects
				(font
					(size 1.27 1.27)
					(thickness 0.15)
				)
				(justify left bottom)
				(hide yes)
			)
		)
		(property "Val" "22R"
			(at 291.465 139.7 0)
			(effects
				(font
					(size 1.27 1.27)
					(thickness 0.15)
				)
			)
		)
		(property "License" "Apache-2.0"
			(at 304.8 166.37 0)
			(effects
				(font
					(size 1.27 1.27)
					(thickness 0.15)
				)
				(justify left bottom)
				(hide yes)
			)
		)
		(property "Author" "Antmicro"
			(at 304.8 168.91 0)
			(effects
				(font
					(size 1.27 1.27)
					(thickness 0.15)
				)
				(justify left bottom)
				(hide yes)
			)
		)
		(property "Tolerance" "1%"
			(at 304.8 151.13 0)
			(effects
				(font
					(size 1.27 1.27)
				)
				(justify left bottom)
				(hide yes)
			)
		)
		(pin "1"
		)
		(pin "2"
		)
		(instances
			(project "data-center-rdimm-ddr5-tester"
				(path ""
					(reference "R48")
					(unit 1)
				)
			)
		)
	)
	(symbol
		(lib_id "antmicropower:GND")
		(at 87.63 195.58 0)
		(unit 1)
		(exclude_from_sim no)
		(in_bom yes)
		(on_board yes)
		(dnp no)
		(fields_autoplaced yes)
		(property "Reference" "#PWR0234"
			(at 87.63 201.93 0)
			(effects
				(font
					(size 1.27 1.27)
				)
				(hide yes)
			)
		)
		(property "Value" "GND"
			(at 85.725 200.025 0)
			(effects
				(font
					(size 1.27 1.27)
					(thickness 0.15)
				)
				(justify left bottom)
			)
		)
		(property "Footprint" ""
			(at 96.52 203.2 0)
			(effects
				(font
					(size 1.27 1.27)
					(thickness 0.15)
				)
				(justify left bottom)
				(hide yes)
			)
		)
		(property "Datasheet" ""
			(at 96.52 208.28 0)
			(effects
				(font
					(size 1.27 1.27)
					(thickness 0.15)
				)
				(justify left bottom)
				(hide yes)
			)
		)
		(property "Description" ""
			(at 87.63 195.58 0)
			(effects
				(font
					(size 1.27 1.27)
				)
				(hide yes)
			)
		)
		(property "Author" "Antmicro"
			(at 96.52 200.66 0)
			(effects
				(font
					(size 1.27 1.27)
					(thickness 0.15)
				)
				(justify left bottom)
				(hide yes)
			)
		)
		(property "License" "Apache-2.0"
			(at 96.52 203.2 0)
			(effects
				(font
					(size 1.27 1.27)
					(thickness 0.15)
				)
				(justify left bottom)
				(hide yes)
			)
		)
		(pin "1"
		)
		(instances
			(project "data-center-rdimm-ddr5-tester"
				(path ""
					(reference "#PWR0234")
					(unit 1)
				)
			)
		)
	)
	(symbol
		(lib_id "antmicroTestPoints:TP_1mm_SMD")
		(at 166.37 138.43 0)
		(unit 1)
		(exclude_from_sim no)
		(in_bom no)
		(on_board yes)
		(dnp no)
		(property "Reference" "TP1"
			(at 173.355 138.43 0)
			(effects
				(font
					(size 1.27 1.27)
				)
			)
		)
		(property "Value" "TP_1mm_SMD"
			(at 181.61 146.05 0)
			(effects
				(font
					(size 1.27 1.27)
					(thickness 0.15)
				)
				(justify left bottom)
				(hide yes)
			)
		)
		(property "Footprint" "antmicro-footprints:TP_SMD_1mm"
			(at 181.61 148.59 0)
			(effects
				(font
					(size 1.27 1.27)
					(thickness 0.15)
				)
				(justify left bottom)
				(hide yes)
			)
		)
		(property "Datasheet" ""
			(at 181.61 151.13 0)
			(effects
				(font
					(size 1.27 1.27)
					(thickness 0.15)
				)
				(justify left bottom)
				(hide yes)
			)
		)
		(property "Description" ""
			(at 166.37 138.43 0)
			(effects
				(font
					(size 1.27 1.27)
				)
				(hide yes)
			)
		)
		(property "MPN" ""
			(at 166.37 138.43 0)
			(effects
				(font
					(size 1.27 1.27)
				)
				(hide yes)
			)
		)
		(property "Manufacturer" ""
			(at 166.37 138.43 0)
			(effects
				(font
					(size 1.27 1.27)
				)
				(hide yes)
			)
		)
		(property "Author" "Antmicro"
			(at 181.61 153.67 0)
			(effects
				(font
					(size 1.27 1.27)
					(thickness 0.15)
				)
				(justify left bottom)
				(hide yes)
			)
		)
		(property "License" "Apache-2.0"
			(at 181.61 156.21 0)
			(effects
				(font
					(size 1.27 1.27)
					(thickness 0.15)
				)
				(justify left bottom)
				(hide yes)
			)
		)
		(pin "1"
		)
		(instances
			(project "data-center-rdimm-ddr5-tester"
				(path ""
					(reference "TP1")
					(unit 1)
				)
			)
		)
	)
	(symbol
		(lib_id "antmicropower:GND")
		(at 233.68 67.31 0)
		(mirror y)
		(unit 1)
		(exclude_from_sim no)
		(in_bom yes)
		(on_board yes)
		(dnp no)
		(property "Reference" "#PWR0212"
			(at 233.68 73.66 0)
			(effects
				(font
					(size 1.27 1.27)
				)
				(hide yes)
			)
		)
		(property "Value" "GND"
			(at 235.585 71.755 0)
			(effects
				(font
					(size 1.27 1.27)
					(thickness 0.15)
				)
				(justify left bottom)
			)
		)
		(property "Footprint" ""
			(at 224.79 74.93 0)
			(effects
				(font
					(size 1.27 1.27)
					(thickness 0.15)
				)
				(justify left bottom)
				(hide yes)
			)
		)
		(property "Datasheet" ""
			(at 224.79 80.01 0)
			(effects
				(font
					(size 1.27 1.27)
					(thickness 0.15)
				)
				(justify left bottom)
				(hide yes)
			)
		)
		(property "Description" ""
			(at 233.68 67.31 0)
			(effects
				(font
					(size 1.27 1.27)
				)
				(hide yes)
			)
		)
		(property "Author" "Antmicro"
			(at 224.79 72.39 0)
			(effects
				(font
					(size 1.27 1.27)
					(thickness 0.15)
				)
				(justify left bottom)
				(hide yes)
			)
		)
		(property "License" "Apache-2.0"
			(at 224.79 74.93 0)
			(effects
				(font
					(size 1.27 1.27)
					(thickness 0.15)
				)
				(justify left bottom)
				(hide yes)
			)
		)
		(pin "1"
		)
		(instances
			(project "data-center-rdimm-ddr5-tester"
				(path ""
					(reference "#PWR0212")
					(unit 1)
				)
			)
		)
	)
	(symbol
		(lib_id "antmicroCapacitors0402:C_100n_0402")
		(at 384.81 205.74 90)
		(unit 1)
		(exclude_from_sim no)
		(in_bom yes)
		(on_board yes)
		(dnp no)
		(fields_autoplaced yes)
		(property "Reference" "C236"
			(at 387.1341 202.363 90)
			(effects
				(font
					(size 1.27 1.27)
					(thickness 0.15)
				)
				(justify right)
			)
		)
		(property "Value" "C_100n_0402"
			(at 394.97 185.42 0)
			(effects
				(font
					(size 1.27 1.27)
					(thickness 0.15)
				)
				(justify left bottom)
				(hide yes)
			)
		)
		(property "Footprint" "antmicro-footprints:C_0402_1005Metric"
			(at 397.51 185.42 0)
			(effects
				(font
					(size 1.27 1.27)
					(thickness 0.15)
				)
				(justify left bottom)
				(hide yes)
			)
		)
		(property "Datasheet" "https://www.murata.com/products/productdetail?partno=GRM155R61H104KE14%23"
			(at 400.05 185.42 0)
			(effects
				(font
					(size 1.27 1.27)
					(thickness 0.15)
				)
				(justify left bottom)
				(hide yes)
			)
		)
		(property "Description" ""
			(at 384.81 205.74 0)
			(effects
				(font
					(size 1.27 1.27)
				)
				(hide yes)
			)
		)
		(property "MPN" "GRM155R61H104KE14D"
			(at 402.59 185.42 0)
			(effects
				(font
					(size 1.27 1.27)
					(thickness 0.15)
				)
				(justify left bottom)
				(hide yes)
			)
		)
		(property "Manufacturer" "Murata"
			(at 405.13 185.42 0)
			(effects
				(font
					(size 1.27 1.27)
					(thickness 0.15)
				)
				(justify left bottom)
				(hide yes)
			)
		)
		(property "License" "Apache-2.0"
			(at 407.67 185.42 0)
			(effects
				(font
					(size 1.27 1.27)
					(thickness 0.15)
				)
				(justify left bottom)
				(hide yes)
			)
		)
		(property "Author" "Antmicro"
			(at 410.21 185.42 0)
			(effects
				(font
					(size 1.27 1.27)
					(thickness 0.15)
				)
				(justify left bottom)
				(hide yes)
			)
		)
		(property "Val" "100n"
			(at 387.1341 204.8867 90)
			(effects
				(font
					(size 1.27 1.27)
					(thickness 0.15)
				)
				(justify right)
			)
		)
		(property "Voltage" "50V"
			(at 412.75 185.42 0)
			(effects
				(font
					(size 1.27 1.27)
				)
				(justify left bottom)
				(hide yes)
			)
		)
		(property "Dielectric" "X5R"
			(at 415.29 185.42 0)
			(effects
				(font
					(size 1.27 1.27)
				)
				(justify left bottom)
				(hide yes)
			)
		)
		(pin "1"
		)
		(pin "2"
		)
		(instances
			(project "data-center-rdimm-ddr5-tester"
				(path ""
					(reference "C236")
					(unit 1)
				)
			)
		)
	)
	(symbol
		(lib_id "antmicroResistors0402:R_5k11_0402")
		(at 72.39 44.45 0)
		(mirror y)
		(unit 1)
		(exclude_from_sim no)
		(in_bom yes)
		(on_board yes)
		(dnp no)
		(property "Reference" "R68"
			(at 74.295 43.18 0)
			(effects
				(font
					(size 1.27 1.27)
				)
			)
		)
		(property "Value" "R_5k11_0402"
			(at 52.07 57.15 0)
			(effects
				(font
					(size 1.27 1.27)
					(thickness 0.15)
				)
				(justify left bottom)
				(hide yes)
			)
		)
		(property "Footprint" "antmicro-footprints:R_0402_1005Metric"
			(at 52.07 59.69 0)
			(effects
				(font
					(size 1.27 1.27)
					(thickness 0.15)
				)
				(justify left bottom)
				(hide yes)
			)
		)
		(property "Datasheet" "https://www.bourns.com/docs/product-datasheets/cr.pdf"
			(at 52.07 62.23 0)
			(effects
				(font
					(size 1.27 1.27)
					(thickness 0.15)
				)
				(justify left bottom)
				(hide yes)
			)
		)
		(property "Description" ""
			(at 72.39 44.45 0)
			(effects
				(font
					(size 1.27 1.27)
				)
				(hide yes)
			)
		)
		(property "Manufacturer" "Bourns"
			(at 52.07 67.31 0)
			(effects
				(font
					(size 1.27 1.27)
					(thickness 0.15)
				)
				(justify left bottom)
				(hide yes)
			)
		)
		(property "MPN" "CR0402-FX-5111GLF"
			(at 52.07 64.77 0)
			(effects
				(font
					(size 1.27 1.27)
					(thickness 0.15)
				)
				(justify left bottom)
				(hide yes)
			)
		)
		(property "Val" "5k11"
			(at 69.85 42.545 0)
			(effects
				(font
					(size 1.27 1.27)
					(thickness 0.15)
				)
			)
		)
		(property "License" "Apache-2.0"
			(at 52.07 69.85 0)
			(effects
				(font
					(size 1.27 1.27)
					(thickness 0.15)
				)
				(justify left bottom)
				(hide yes)
			)
		)
		(property "Author" "Antmicro"
			(at 52.07 72.39 0)
			(effects
				(font
					(size 1.27 1.27)
					(thickness 0.15)
				)
				(justify left bottom)
				(hide yes)
			)
		)
		(property "Tolerance" "1%"
			(at 52.07 54.61 0)
			(effects
				(font
					(size 1.27 1.27)
				)
				(justify left bottom)
				(hide yes)
			)
		)
		(pin "1"
		)
		(pin "2"
		)
		(instances
			(project "data-center-rdimm-ddr5-tester"
				(path ""
					(reference "R68")
					(unit 1)
				)
			)
		)
	)
	(symbol
		(lib_id "antmicropower:GND")
		(at 384.81 143.51 0)
		(unit 1)
		(exclude_from_sim no)
		(in_bom yes)
		(on_board yes)
		(dnp no)
		(property "Reference" "#PWR0197"
			(at 384.81 149.86 0)
			(effects
				(font
					(size 1.27 1.27)
				)
				(hide yes)
			)
		)
		(property "Value" "GND"
			(at 382.905 147.955 0)
			(effects
				(font
					(size 1.27 1.27)
					(thickness 0.15)
				)
				(justify left bottom)
			)
		)
		(property "Footprint" ""
			(at 393.7 151.13 0)
			(effects
				(font
					(size 1.27 1.27)
					(thickness 0.15)
				)
				(justify left bottom)
				(hide yes)
			)
		)
		(property "Datasheet" ""
			(at 393.7 156.21 0)
			(effects
				(font
					(size 1.27 1.27)
					(thickness 0.15)
				)
				(justify left bottom)
				(hide yes)
			)
		)
		(property "Description" ""
			(at 384.81 143.51 0)
			(effects
				(font
					(size 1.27 1.27)
				)
				(hide yes)
			)
		)
		(property "Author" "Antmicro"
			(at 393.7 148.59 0)
			(effects
				(font
					(size 1.27 1.27)
					(thickness 0.15)
				)
				(justify left bottom)
				(hide yes)
			)
		)
		(property "License" "Apache-2.0"
			(at 393.7 151.13 0)
			(effects
				(font
					(size 1.27 1.27)
					(thickness 0.15)
				)
				(justify left bottom)
				(hide yes)
			)
		)
		(pin "1"
		)
		(instances
			(project "data-center-rdimm-ddr5-tester"
				(path ""
					(reference "#PWR0197")
					(unit 1)
				)
			)
		)
	)
	(symbol
		(lib_id "antmicroResistors0402:R_22R_0402")
		(at 173.99 149.86 0)
		(unit 1)
		(exclude_from_sim no)
		(in_bom no)
		(on_board yes)
		(dnp yes)
		(property "Reference" "R57"
			(at 180.975 148.59 0)
			(effects
				(font
					(size 1.27 1.27)
				)
			)
		)
		(property "Value" "R_22R_0402"
			(at 194.31 162.56 0)
			(effects
				(font
					(size 1.27 1.27)
					(thickness 0.15)
				)
				(justify left bottom)
				(hide yes)
			)
		)
		(property "Footprint" "antmicro-footprints:R_0402_1005Metric"
			(at 194.31 165.1 0)
			(effects
				(font
					(size 1.27 1.27)
					(thickness 0.15)
				)
				(justify left bottom)
				(hide yes)
			)
		)
		(property "Datasheet" "https://www.bourns.com/docs/product-datasheets/cr.pdf"
			(at 194.31 167.64 0)
			(effects
				(font
					(size 1.27 1.27)
					(thickness 0.15)
				)
				(justify left bottom)
				(hide yes)
			)
		)
		(property "Description" ""
			(at 173.99 149.86 0)
			(effects
				(font
					(size 1.27 1.27)
				)
				(hide yes)
			)
		)
		(property "Manufacturer" "Bourns"
			(at 194.31 172.72 0)
			(effects
				(font
					(size 1.27 1.27)
					(thickness 0.15)
				)
				(justify left bottom)
				(hide yes)
			)
		)
		(property "MPN" "CR0402-FX-22R0GLF"
			(at 194.31 170.18 0)
			(effects
				(font
					(size 1.27 1.27)
					(thickness 0.15)
				)
				(justify left bottom)
				(hide yes)
			)
		)
		(property "Val" "22R"
			(at 172.085 148.59 0)
			(effects
				(font
					(size 1.27 1.27)
					(thickness 0.15)
				)
			)
		)
		(property "License" "Apache-2.0"
			(at 194.31 175.26 0)
			(effects
				(font
					(size 1.27 1.27)
					(thickness 0.15)
				)
				(justify left bottom)
				(hide yes)
			)
		)
		(property "Author" "Antmicro"
			(at 194.31 177.8 0)
			(effects
				(font
					(size 1.27 1.27)
					(thickness 0.15)
				)
				(justify left bottom)
				(hide yes)
			)
		)
		(property "Tolerance" "1%"
			(at 194.31 160.02 0)
			(effects
				(font
					(size 1.27 1.27)
				)
				(justify left bottom)
				(hide yes)
			)
		)
		(pin "1"
		)
		(pin "2"
		)
		(instances
			(project "data-center-rdimm-ddr5-tester"
				(path ""
					(reference "R57")
					(unit 1)
				)
			)
		)
	)
	(symbol
		(lib_id "antmicropower:+3V3")
		(at 384.81 217.17 0)
		(unit 1)
		(exclude_from_sim no)
		(in_bom yes)
		(on_board yes)
		(dnp no)
		(property "Reference" "#PWR016"
			(at 384.81 220.98 0)
			(effects
				(font
					(size 1.27 1.27)
				)
				(hide yes)
			)
		)
		(property "Value" "+3V3"
			(at 381.635 214.63 0)
			(effects
				(font
					(size 1.27 1.27)
					(thickness 0.15)
				)
				(justify left bottom)
			)
		)
		(property "Footprint" ""
			(at 400.05 224.79 0)
			(effects
				(font
					(size 1.27 1.27)
					(thickness 0.15)
				)
				(justify left bottom)
				(hide yes)
			)
		)
		(property "Datasheet" ""
			(at 400.05 227.33 0)
			(effects
				(font
					(size 1.27 1.27)
					(thickness 0.15)
				)
				(justify left bottom)
				(hide yes)
			)
		)
		(property "Description" ""
			(at 384.81 217.17 0)
			(effects
				(font
					(size 1.27 1.27)
				)
				(hide yes)
			)
		)
		(property "Author" "Antmicro"
			(at 400.05 219.71 0)
			(effects
				(font
					(size 1.27 1.27)
					(thickness 0.15)
				)
				(justify left bottom)
				(hide yes)
			)
		)
		(property "License" "Apache-2.0"
			(at 400.05 222.25 0)
			(effects
				(font
					(size 1.27 1.27)
					(thickness 0.15)
				)
				(justify left bottom)
				(hide yes)
			)
		)
		(pin "1"
		)
		(instances
			(project "data-center-rdimm-ddr5-tester"
				(path ""
					(reference "#PWR016")
					(unit 1)
				)
			)
		)
	)
	(symbol
		(lib_id "antmicropower:+1V8")
		(at 384.81 134.62 0)
		(unit 1)
		(exclude_from_sim no)
		(in_bom yes)
		(on_board yes)
		(dnp no)
		(fields_autoplaced yes)
		(property "Reference" "#PWR0237"
			(at 400.05 137.16 0)
			(effects
				(font
					(size 1.27 1.27)
					(thickness 0.15)
				)
				(justify left bottom)
				(hide yes)
			)
		)
		(property "Value" "+1V8"
			(at 384.81 129.54 0)
			(effects
				(font
					(size 1.27 1.27)
					(thickness 0.15)
				)
			)
		)
		(property "Footprint" ""
			(at 400.05 142.24 0)
			(effects
				(font
					(size 1.27 1.27)
					(thickness 0.15)
				)
				(justify left bottom)
				(hide yes)
			)
		)
		(property "Datasheet" ""
			(at 400.05 144.78 0)
			(effects
				(font
					(size 1.27 1.27)
					(thickness 0.15)
				)
				(justify left bottom)
				(hide yes)
			)
		)
		(property "Description" ""
			(at 384.81 134.62 0)
			(effects
				(font
					(size 1.27 1.27)
				)
				(hide yes)
			)
		)
		(property "Author" "Antmicro"
			(at 400.05 139.7 0)
			(effects
				(font
					(size 1.27 1.27)
					(thickness 0.15)
				)
				(justify left bottom)
				(hide yes)
			)
		)
		(property "License" "Apache-2.0"
			(at 400.05 142.24 0)
			(effects
				(font
					(size 1.27 1.27)
					(thickness 0.15)
				)
				(justify left bottom)
				(hide yes)
			)
		)
		(pin "1"
		)
		(instances
			(project "data-center-rdimm-ddr5-tester"
				(path ""
					(reference "#PWR0237")
					(unit 1)
				)
			)
		)
	)
	(symbol
		(lib_id "antmicroTVSDiodes:TPD4E05U06QDQARQ1")
		(at 142.24 52.07 0)
		(mirror y)
		(unit 1)
		(exclude_from_sim no)
		(in_bom yes)
		(on_board yes)
		(dnp no)
		(property "Reference" "U8"
			(at 132.08 55.245 0)
			(effects
				(font
					(size 1.27 1.27)
					(thickness 0.15)
				)
				(justify left)
			)
		)
		(property "Value" "TPD4E05U06QDQARQ1"
			(at 118.11 62.23 0)
			(effects
				(font
					(size 1.27 1.27)
					(thickness 0.15)
				)
				(justify left bottom)
				(hide yes)
			)
		)
		(property "Footprint" "antmicro-footprints:USON-10_2.5x1mm_P0.5mm"
			(at 118.11 57.15 0)
			(effects
				(font
					(size 1.27 1.27)
					(thickness 0.15)
				)
				(justify left bottom)
				(hide yes)
			)
		)
		(property "Datasheet" "https://www.ti.com/lit/ds/symlink/tpd4e05u06-q1.pdf?HQS=dis-mous-null-mousermode-dsf-pf-null-wwe&ts=1663591265741&ref_url=https%253A%252F%252Fwww.mouser.com%252F"
			(at 118.11 59.69 0)
			(effects
				(font
					(size 1.27 1.27)
					(thickness 0.15)
				)
				(justify left bottom)
				(hide yes)
			)
		)
		(property "Description" ""
			(at 142.24 52.07 0)
			(effects
				(font
					(size 1.27 1.27)
				)
				(hide yes)
			)
		)
		(property "MPN" "TPD4E05U06QDQARQ1"
			(at 132.08 57.785 0)
			(effects
				(font
					(size 1.27 1.27)
					(thickness 0.15)
				)
				(justify left)
			)
		)
		(property "Manufacturer" "Texas Instruments"
			(at 118.11 64.77 0)
			(effects
				(font
					(size 1.27 1.27)
					(thickness 0.15)
				)
				(justify left bottom)
				(hide yes)
			)
		)
		(property "Author" "Antmicro"
			(at 118.11 67.31 0)
			(effects
				(font
					(size 1.27 1.27)
					(thickness 0.15)
				)
				(justify left bottom)
				(hide yes)
			)
		)
		(property "License" "Apache-2.0"
			(at 118.11 69.85 0)
			(effects
				(font
					(size 1.27 1.27)
					(thickness 0.15)
				)
				(justify left bottom)
				(hide yes)
			)
		)
		(pin "8"
		)
		(pin "1"
		)
		(pin "7"
		)
		(pin "4"
		)
		(pin "2"
		)
		(pin "3"
		)
		(pin "6"
		)
		(pin "10"
		)
		(pin "9"
		)
		(pin "5"
		)
		(instances
			(project "data-center-rdimm-ddr5-tester"
				(path ""
					(reference "U8")
					(unit 1)
				)
			)
		)
	)
	(symbol
		(lib_id "antmicroLEDIndicationDiscrete:LED_G_0402_VLMTG1500-GS08")
		(at 269.24 67.31 90)
		(unit 1)
		(exclude_from_sim no)
		(in_bom yes)
		(on_board yes)
		(dnp no)
		(fields_autoplaced yes)
		(property "Reference" "D17"
			(at 271.145 63.5 90)
			(effects
				(font
					(size 1.27 1.27)
					(thickness 0.15)
				)
				(justify right)
			)
		)
		(property "Value" "LED_G_0402_VLMTG1500-GS08"
			(at 276.86 44.45 0)
			(effects
				(font
					(size 1.27 1.27)
					(thickness 0.15)
				)
				(justify left bottom)
				(hide yes)
			)
		)
		(property "Footprint" "antmicro-footprints:LED_0402_1005Metric_G"
			(at 279.4 44.45 0)
			(effects
				(font
					(size 1.27 1.27)
					(thickness 0.15)
				)
				(justify left bottom)
				(hide yes)
			)
		)
		(property "Datasheet" "https://www.vishay.com/docs/82554/vlmo1500.pdf"
			(at 281.94 44.45 0)
			(effects
				(font
					(size 1.27 1.27)
					(thickness 0.15)
				)
				(justify left bottom)
				(hide yes)
			)
		)
		(property "Description" ""
			(at 269.24 67.31 0)
			(effects
				(font
					(size 1.27 1.27)
				)
				(hide yes)
			)
		)
		(property "MPN" "VLMTG1500-GS08"
			(at 284.48 44.45 0)
			(effects
				(font
					(size 1.27 1.27)
					(thickness 0.15)
				)
				(justify left bottom)
				(hide yes)
			)
		)
		(property "Manufacturer" "Vishay"
			(at 287.02 44.45 0)
			(effects
				(font
					(size 1.27 1.27)
					(thickness 0.15)
				)
				(justify left bottom)
				(hide yes)
			)
		)
		(property "Color" "Green"
			(at 271.145 66.04 90)
			(effects
				(font
					(size 1.27 1.27)
				)
				(justify right)
			)
		)
		(property "Author" "Antmicro"
			(at 289.56 44.45 0)
			(effects
				(font
					(size 1.27 1.27)
					(thickness 0.15)
				)
				(justify left bottom)
				(hide yes)
			)
		)
		(property "License" "Apache-2.0"
			(at 292.1 44.45 0)
			(effects
				(font
					(size 1.27 1.27)
					(thickness 0.15)
				)
				(justify left bottom)
				(hide yes)
			)
		)
		(pin "1"
		)
		(pin "2"
		)
		(instances
			(project "data-center-rdimm-ddr5-tester"
				(path ""
					(reference "D17")
					(unit 1)
				)
			)
		)
	)
	(symbol
		(lib_id "antmicroLogicTranslatorsLevelShifters:TXU0304BQAR")
		(at 257.81 133.35 0)
		(unit 1)
		(exclude_from_sim no)
		(in_bom yes)
		(on_board yes)
		(dnp no)
		(fields_autoplaced yes)
		(property "Reference" "U7"
			(at 266.7 126.365 0)
			(effects
				(font
					(size 1.27 1.27)
					(thickness 0.15)
				)
			)
		)
		(property "Value" "TXU0304BQAR"
			(at 289.56 135.89 0)
			(effects
				(font
					(size 1.27 1.27)
					(thickness 0.15)
				)
				(justify left bottom)
				(hide yes)
			)
		)
		(property "Footprint" "antmicro-footprints:DHVQFN-14-1EP_2.5x3mm"
			(at 289.56 138.43 0)
			(effects
				(font
					(size 1.27 1.27)
					(thickness 0.15)
				)
				(justify left bottom)
				(hide yes)
			)
		)
		(property "Datasheet" "https://www.ti.com/lit/ds/symlink/txu0304.pdf?ts=1637748643258&ref_url=https%253A%252F%252Fwww.ti.com%252Fproduct%252FTXU0304"
			(at 289.56 140.97 0)
			(effects
				(font
					(size 1.27 1.27)
					(thickness 0.15)
				)
				(justify left bottom)
				(hide yes)
			)
		)
		(property "Description" ""
			(at 257.81 133.35 0)
			(effects
				(font
					(size 1.27 1.27)
				)
				(hide yes)
			)
		)
		(property "MPN" "TXU0304BQAR"
			(at 266.7 128.905 0)
			(effects
				(font
					(size 1.27 1.27)
					(thickness 0.15)
				)
			)
		)
		(property "Manufacturer" "Texas Instruments"
			(at 289.56 146.05 0)
			(effects
				(font
					(size 1.27 1.27)
					(thickness 0.15)
				)
				(justify left bottom)
				(hide yes)
			)
		)
		(property "Author" "Antmicro"
			(at 289.56 148.59 0)
			(effects
				(font
					(size 1.27 1.27)
					(thickness 0.15)
				)
				(justify left bottom)
				(hide yes)
			)
		)
		(property "License" "Apache-2.0"
			(at 289.56 151.13 0)
			(effects
				(font
					(size 1.27 1.27)
					(thickness 0.15)
				)
				(justify left bottom)
				(hide yes)
			)
		)
		(pin "2"
		)
		(pin "11"
		)
		(pin "1"
		)
		(pin "14"
		)
		(pin "9"
		)
		(pin "6"
		)
		(pin "10"
		)
		(pin "5"
		)
		(pin "4"
		)
		(pin "8"
		)
		(pin "12"
		)
		(pin "3"
		)
		(pin "15"
		)
		(pin "7"
		)
		(pin "13"
		)
		(instances
			(project "data-center-rdimm-ddr5-tester"
				(path ""
					(reference "U7")
					(unit 1)
				)
			)
		)
	)
	(symbol
		(lib_id "antmicropower:GND")
		(at 276.86 233.68 0)
		(mirror y)
		(unit 1)
		(exclude_from_sim no)
		(in_bom yes)
		(on_board yes)
		(dnp no)
		(property "Reference" "#PWR09"
			(at 276.86 240.03 0)
			(effects
				(font
					(size 1.27 1.27)
				)
				(hide yes)
			)
		)
		(property "Value" "GND"
			(at 278.765 238.125 0)
			(effects
				(font
					(size 1.27 1.27)
					(thickness 0.15)
				)
				(justify left bottom)
			)
		)
		(property "Footprint" ""
			(at 267.97 241.3 0)
			(effects
				(font
					(size 1.27 1.27)
					(thickness 0.15)
				)
				(justify left bottom)
				(hide yes)
			)
		)
		(property "Datasheet" ""
			(at 267.97 246.38 0)
			(effects
				(font
					(size 1.27 1.27)
					(thickness 0.15)
				)
				(justify left bottom)
				(hide yes)
			)
		)
		(property "Description" ""
			(at 276.86 233.68 0)
			(effects
				(font
					(size 1.27 1.27)
				)
				(hide yes)
			)
		)
		(property "Author" "Antmicro"
			(at 267.97 238.76 0)
			(effects
				(font
					(size 1.27 1.27)
					(thickness 0.15)
				)
				(justify left bottom)
				(hide yes)
			)
		)
		(property "License" "Apache-2.0"
			(at 267.97 241.3 0)
			(effects
				(font
					(size 1.27 1.27)
					(thickness 0.15)
				)
				(justify left bottom)
				(hide yes)
			)
		)
		(pin "1"
		)
		(instances
			(project "data-center-rdimm-ddr5-tester"
				(path ""
					(reference "#PWR09")
					(unit 1)
				)
			)
		)
	)
	(symbol
		(lib_id "antmicropower:GND")
		(at 269.24 76.2 0)
		(unit 1)
		(exclude_from_sim no)
		(in_bom yes)
		(on_board yes)
		(dnp no)
		(fields_autoplaced yes)
		(property "Reference" "#PWR0509"
			(at 269.24 82.55 0)
			(effects
				(font
					(size 1.27 1.27)
				)
				(hide yes)
			)
		)
		(property "Value" "GND"
			(at 267.335 80.645 0)
			(effects
				(font
					(size 1.27 1.27)
					(thickness 0.15)
				)
				(justify left bottom)
			)
		)
		(property "Footprint" ""
			(at 278.13 83.82 0)
			(effects
				(font
					(size 1.27 1.27)
					(thickness 0.15)
				)
				(justify left bottom)
				(hide yes)
			)
		)
		(property "Datasheet" ""
			(at 278.13 88.9 0)
			(effects
				(font
					(size 1.27 1.27)
					(thickness 0.15)
				)
				(justify left bottom)
				(hide yes)
			)
		)
		(property "Description" ""
			(at 269.24 76.2 0)
			(effects
				(font
					(size 1.27 1.27)
				)
				(hide yes)
			)
		)
		(property "Author" "Antmicro"
			(at 278.13 81.28 0)
			(effects
				(font
					(size 1.27 1.27)
					(thickness 0.15)
				)
				(justify left bottom)
				(hide yes)
			)
		)
		(property "License" "Apache-2.0"
			(at 278.13 83.82 0)
			(effects
				(font
					(size 1.27 1.27)
					(thickness 0.15)
				)
				(justify left bottom)
				(hide yes)
			)
		)
		(pin "1"
		)
		(instances
			(project "data-center-rdimm-ddr5-tester"
				(path ""
					(reference "#PWR0509")
					(unit 1)
				)
			)
		)
	)
	(symbol
		(lib_id "antmicroResistors0402:R_0R_0402")
		(at 293.37 167.64 180)
		(unit 1)
		(exclude_from_sim no)
		(in_bom no)
		(on_board yes)
		(dnp yes)
		(property "Reference" "R91"
			(at 295.91 166.37 0)
			(effects
				(font
					(size 1.27 1.27)
				)
			)
		)
		(property "Value" "R_0R_0402"
			(at 273.05 154.94 0)
			(effects
				(font
					(size 1.27 1.27)
					(thickness 0.15)
				)
				(justify left bottom)
				(hide yes)
			)
		)
		(property "Footprint" "antmicro-footprints:R_0402_1005Metric"
			(at 273.05 152.4 0)
			(effects
				(font
					(size 1.27 1.27)
					(thickness 0.15)
				)
				(justify left bottom)
				(hide yes)
			)
		)
		(property "Datasheet" "https://industrial.panasonic.com/cdbs/www-data/pdf/RDA0000/AOA0000C301.pdf"
			(at 273.05 149.86 0)
			(effects
				(font
					(size 1.27 1.27)
					(thickness 0.15)
				)
				(justify left bottom)
				(hide yes)
			)
		)
		(property "Description" ""
			(at 293.37 167.64 0)
			(effects
				(font
					(size 1.27 1.27)
				)
				(hide yes)
			)
		)
		(property "Manufacturer" "Panasonic"
			(at 273.05 144.78 0)
			(effects
				(font
					(size 1.27 1.27)
					(thickness 0.15)
				)
				(justify left bottom)
				(hide yes)
			)
		)
		(property "MPN" "ERJ2GE0R00X"
			(at 273.05 147.32 0)
			(effects
				(font
					(size 1.27 1.27)
					(thickness 0.15)
				)
				(justify left bottom)
				(hide yes)
			)
		)
		(property "Val" "0R"
			(at 287.02 166.37 0)
			(effects
				(font
					(size 1.27 1.27)
					(thickness 0.15)
				)
			)
		)
		(property "License" "Apache-2.0"
			(at 273.05 142.24 0)
			(effects
				(font
					(size 1.27 1.27)
					(thickness 0.15)
				)
				(justify left bottom)
				(hide yes)
			)
		)
		(property "Author" "Antmicro"
			(at 273.05 139.7 0)
			(effects
				(font
					(size 1.27 1.27)
					(thickness 0.15)
				)
				(justify left bottom)
				(hide yes)
			)
		)
		(property "Tolerance" "~"
			(at 273.05 157.48 0)
			(effects
				(font
					(size 1.27 1.27)
				)
				(justify left bottom)
				(hide yes)
			)
		)
		(property "Current" "1A"
			(at 290.83 179.705 0)
			(effects
				(font
					(size 1.27 1.27)
					(thickness 0.15)
				)
				(hide yes)
			)
		)
		(pin "1"
		)
		(pin "2"
		)
		(instances
			(project "data-center-rdimm-ddr5-tester"
				(path ""
					(reference "R91")
					(unit 1)
				)
			)
		)
	)
	(symbol
		(lib_id "antmicropower:GND")
		(at 198.12 67.31 0)
		(mirror y)
		(unit 1)
		(exclude_from_sim no)
		(in_bom yes)
		(on_board yes)
		(dnp no)
		(fields_autoplaced yes)
		(property "Reference" "#PWR0207"
			(at 198.12 73.66 0)
			(effects
				(font
					(size 1.27 1.27)
				)
				(hide yes)
			)
		)
		(property "Value" "GND"
			(at 200.025 71.755 0)
			(effects
				(font
					(size 1.27 1.27)
					(thickness 0.15)
				)
				(justify left bottom)
			)
		)
		(property "Footprint" ""
			(at 189.23 74.93 0)
			(effects
				(font
					(size 1.27 1.27)
					(thickness 0.15)
				)
				(justify left bottom)
				(hide yes)
			)
		)
		(property "Datasheet" ""
			(at 189.23 80.01 0)
			(effects
				(font
					(size 1.27 1.27)
					(thickness 0.15)
				)
				(justify left bottom)
				(hide yes)
			)
		)
		(property "Description" ""
			(at 198.12 67.31 0)
			(effects
				(font
					(size 1.27 1.27)
				)
				(hide yes)
			)
		)
		(property "Author" "Antmicro"
			(at 189.23 72.39 0)
			(effects
				(font
					(size 1.27 1.27)
					(thickness 0.15)
				)
				(justify left bottom)
				(hide yes)
			)
		)
		(property "License" "Apache-2.0"
			(at 189.23 74.93 0)
			(effects
				(font
					(size 1.27 1.27)
					(thickness 0.15)
				)
				(justify left bottom)
				(hide yes)
			)
		)
		(pin "1"
		)
		(instances
			(project "data-center-rdimm-ddr5-tester"
				(path ""
					(reference "#PWR0207")
					(unit 1)
				)
			)
		)
	)
	(symbol
		(lib_id "antmicroResistors0402:R_0R_0402")
		(at 303.53 170.18 0)
		(unit 1)
		(exclude_from_sim no)
		(in_bom yes)
		(on_board yes)
		(dnp no)
		(property "Reference" "R92"
			(at 311.15 168.91 0)
			(effects
				(font
					(size 1.27 1.27)
				)
			)
		)
		(property "Value" "R_0R_0402"
			(at 323.85 182.88 0)
			(effects
				(font
					(size 1.27 1.27)
					(thickness 0.15)
				)
				(justify left bottom)
				(hide yes)
			)
		)
		(property "Footprint" "antmicro-footprints:R_0402_1005Metric"
			(at 323.85 185.42 0)
			(effects
				(font
					(size 1.27 1.27)
					(thickness 0.15)
				)
				(justify left bottom)
				(hide yes)
			)
		)
		(property "Datasheet" "https://industrial.panasonic.com/cdbs/www-data/pdf/RDA0000/AOA0000C301.pdf"
			(at 323.85 187.96 0)
			(effects
				(font
					(size 1.27 1.27)
					(thickness 0.15)
				)
				(justify left bottom)
				(hide yes)
			)
		)
		(property "Description" ""
			(at 303.53 170.18 0)
			(effects
				(font
					(size 1.27 1.27)
				)
				(hide yes)
			)
		)
		(property "Manufacturer" "Panasonic"
			(at 323.85 193.04 0)
			(effects
				(font
					(size 1.27 1.27)
					(thickness 0.15)
				)
				(justify left bottom)
				(hide yes)
			)
		)
		(property "MPN" "ERJ2GE0R00X"
			(at 323.85 190.5 0)
			(effects
				(font
					(size 1.27 1.27)
					(thickness 0.15)
				)
				(justify left bottom)
				(hide yes)
			)
		)
		(property "Val" "0R"
			(at 302.26 168.91 0)
			(effects
				(font
					(size 1.27 1.27)
					(thickness 0.15)
				)
			)
		)
		(property "License" "Apache-2.0"
			(at 323.85 195.58 0)
			(effects
				(font
					(size 1.27 1.27)
					(thickness 0.15)
				)
				(justify left bottom)
				(hide yes)
			)
		)
		(property "Author" "Antmicro"
			(at 323.85 198.12 0)
			(effects
				(font
					(size 1.27 1.27)
					(thickness 0.15)
				)
				(justify left bottom)
				(hide yes)
			)
		)
		(property "Tolerance" "~"
			(at 323.85 180.34 0)
			(effects
				(font
					(size 1.27 1.27)
				)
				(justify left bottom)
				(hide yes)
			)
		)
		(property "Current" "1A"
			(at 306.07 179.07 0)
			(effects
				(font
					(size 1.27 1.27)
					(thickness 0.15)
				)
				(hide yes)
			)
		)
		(pin "1"
		)
		(pin "2"
		)
		(instances
			(project "data-center-rdimm-ddr5-tester"
				(path ""
					(reference "R92")
					(unit 1)
				)
			)
		)
	)
	(symbol
		(lib_id "antmicroCapacitors0603:C_10u_25V_0603")
		(at 198.12 64.77 90)
		(unit 1)
		(exclude_from_sim no)
		(in_bom yes)
		(on_board yes)
		(dnp no)
		(property "Reference" "C109"
			(at 198.755 60.325 90)
			(effects
				(font
					(size 1.27 1.27)
				)
				(justify right)
			)
		)
		(property "Value" "C_10u_25V_0603"
			(at 208.28 44.45 0)
			(effects
				(font
					(size 1.27 1.27)
					(thickness 0.15)
				)
				(justify left bottom)
				(hide yes)
			)
		)
		(property "Footprint" "antmicro-footprints:C_0603_1608Metric"
			(at 210.82 44.45 0)
			(effects
				(font
					(size 1.27 1.27)
					(thickness 0.15)
				)
				(justify left bottom)
				(hide yes)
			)
		)
		(property "Datasheet" "https://product.tdk.com/en/search/capacitor/ceramic/mlcc/info?part_no=C1608X5R1E106M080AC"
			(at 213.36 44.45 0)
			(effects
				(font
					(size 1.27 1.27)
					(thickness 0.15)
				)
				(justify left bottom)
				(hide yes)
			)
		)
		(property "Description" ""
			(at 198.12 64.77 0)
			(effects
				(font
					(size 1.27 1.27)
				)
				(hide yes)
			)
		)
		(property "Manufacturer" "TDK"
			(at 218.44 44.45 0)
			(effects
				(font
					(size 1.27 1.27)
					(thickness 0.15)
				)
				(justify left bottom)
				(hide yes)
			)
		)
		(property "MPN" "C1608X5R1E106M080AC"
			(at 215.9 44.45 0)
			(effects
				(font
					(size 1.27 1.27)
					(thickness 0.15)
				)
				(justify left bottom)
				(hide yes)
			)
		)
		(property "Val" "10u"
			(at 198.755 64.135 90)
			(effects
				(font
					(size 1.27 1.27)
					(thickness 0.15)
				)
				(justify right)
			)
		)
		(property "License" "Apache-2.0"
			(at 220.98 44.45 0)
			(effects
				(font
					(size 1.27 1.27)
					(thickness 0.15)
				)
				(justify left bottom)
				(hide yes)
			)
		)
		(property "Author" "Antmicro"
			(at 223.52 44.45 0)
			(effects
				(font
					(size 1.27 1.27)
					(thickness 0.15)
				)
				(justify left bottom)
				(hide yes)
			)
		)
		(property "Voltage" "25V"
			(at 226.06 44.45 0)
			(effects
				(font
					(size 1.27 1.27)
				)
				(justify left bottom)
				(hide yes)
			)
		)
		(property "Dielectric" ""
			(at 228.6 44.45 0)
			(effects
				(font
					(size 1.27 1.27)
				)
				(justify left bottom)
				(hide yes)
			)
		)
		(pin "1"
		)
		(pin "2"
		)
		(instances
			(project "data-center-rdimm-ddr5-tester"
				(path ""
					(reference "C109")
					(unit 1)
				)
			)
		)
	)
	(symbol
		(lib_id "antmicropower:GND")
		(at 384.81 207.01 0)
		(unit 1)
		(exclude_from_sim no)
		(in_bom yes)
		(on_board yes)
		(dnp no)
		(property "Reference" "#PWR015"
			(at 384.81 213.36 0)
			(effects
				(font
					(size 1.27 1.27)
				)
				(hide yes)
			)
		)
		(property "Value" "GND"
			(at 382.905 211.455 0)
			(effects
				(font
					(size 1.27 1.27)
					(thickness 0.15)
				)
				(justify left bottom)
			)
		)
		(property "Footprint" ""
			(at 393.7 214.63 0)
			(effects
				(font
					(size 1.27 1.27)
					(thickness 0.15)
				)
				(justify left bottom)
				(hide yes)
			)
		)
		(property "Datasheet" ""
			(at 393.7 219.71 0)
			(effects
				(font
					(size 1.27 1.27)
					(thickness 0.15)
				)
				(justify left bottom)
				(hide yes)
			)
		)
		(property "Description" ""
			(at 384.81 207.01 0)
			(effects
				(font
					(size 1.27 1.27)
				)
				(hide yes)
			)
		)
		(property "Author" "Antmicro"
			(at 393.7 212.09 0)
			(effects
				(font
					(size 1.27 1.27)
					(thickness 0.15)
				)
				(justify left bottom)
				(hide yes)
			)
		)
		(property "License" "Apache-2.0"
			(at 393.7 214.63 0)
			(effects
				(font
					(size 1.27 1.27)
					(thickness 0.15)
				)
				(justify left bottom)
				(hide yes)
			)
		)
		(pin "1"
		)
		(instances
			(project "data-center-rdimm-ddr5-tester"
				(path ""
					(reference "#PWR015")
					(unit 1)
				)
			)
		)
	)
	(symbol
		(lib_id "antmicroCoaxialConnectorsRF:U_FL-R-SMT-1")
		(at 326.39 76.2 0)
		(unit 1)
		(exclude_from_sim no)
		(in_bom yes)
		(on_board yes)
		(dnp no)
		(property "Reference" "J14"
			(at 331.47 69.215 0)
			(effects
				(font
					(size 1.27 1.27)
					(thickness 0.15)
				)
				(justify left)
			)
		)
		(property "Value" "U_FL-R-SMT-1"
			(at 346.71 83.82 0)
			(effects
				(font
					(size 1.27 1.27)
					(thickness 0.15)
				)
				(justify left bottom)
				(hide yes)
			)
		)
		(property "Footprint" "antmicro-footprints:Coax_Conn_U.FL"
			(at 346.71 86.36 0)
			(effects
				(font
					(size 1.27 1.27)
					(thickness 0.15)
				)
				(justify left bottom)
				(hide yes)
			)
		)
		(property "Datasheet" "https://media.digikey.com/pdf/Data%20Sheets/Hirose%20PDFs/UFL%20Series.pdf"
			(at 346.71 88.9 0)
			(effects
				(font
					(size 1.27 1.27)
					(thickness 0.15)
				)
				(justify left bottom)
				(hide yes)
			)
		)
		(property "Description" ""
			(at 326.39 76.2 0)
			(effects
				(font
					(size 1.27 1.27)
				)
				(hide yes)
			)
		)
		(property "MPN" "U.FL-R-SMT-1(10)"
			(at 323.85 72.39 0)
			(effects
				(font
					(size 1.27 1.27)
					(thickness 0.15)
				)
				(justify left)
			)
		)
		(property "Manufacturer" "Hirose Electric"
			(at 346.71 91.44 0)
			(effects
				(font
					(size 1.27 1.27)
					(thickness 0.15)
				)
				(justify left bottom)
				(hide yes)
			)
		)
		(property "Author" "Antmicro"
			(at 346.71 93.98 0)
			(effects
				(font
					(size 1.27 1.27)
					(thickness 0.15)
				)
				(justify left bottom)
				(hide yes)
			)
		)
		(property "License" "Apache-2.0"
			(at 346.71 96.52 0)
			(effects
				(font
					(size 1.27 1.27)
					(thickness 0.15)
				)
				(justify left bottom)
				(hide yes)
			)
		)
		(pin "SH2"
		)
		(pin "SH1"
		)
		(pin "1"
		)
		(instances
			(project "data-center-rdimm-ddr5-tester"
				(path ""
					(reference "J14")
					(unit 1)
				)
			)
		)
	)
	(symbol
		(lib_id "antmicroResistors0402:R_0R_0402")
		(at 288.29 165.1 0)
		(unit 1)
		(exclude_from_sim no)
		(in_bom yes)
		(on_board yes)
		(dnp no)
		(property "Reference" "R88"
			(at 295.91 163.83 0)
			(effects
				(font
					(size 1.27 1.27)
				)
			)
		)
		(property "Value" "R_0R_0402"
			(at 308.61 177.8 0)
			(effects
				(font
					(size 1.27 1.27)
					(thickness 0.15)
				)
				(justify left bottom)
				(hide yes)
			)
		)
		(property "Footprint" "antmicro-footprints:R_0402_1005Metric"
			(at 308.61 180.34 0)
			(effects
				(font
					(size 1.27 1.27)
					(thickness 0.15)
				)
				(justify left bottom)
				(hide yes)
			)
		)
		(property "Datasheet" "https://industrial.panasonic.com/cdbs/www-data/pdf/RDA0000/AOA0000C301.pdf"
			(at 308.61 182.88 0)
			(effects
				(font
					(size 1.27 1.27)
					(thickness 0.15)
				)
				(justify left bottom)
				(hide yes)
			)
		)
		(property "Description" ""
			(at 288.29 165.1 0)
			(effects
				(font
					(size 1.27 1.27)
				)
				(hide yes)
			)
		)
		(property "Manufacturer" "Panasonic"
			(at 308.61 187.96 0)
			(effects
				(font
					(size 1.27 1.27)
					(thickness 0.15)
				)
				(justify left bottom)
				(hide yes)
			)
		)
		(property "MPN" "ERJ2GE0R00X"
			(at 308.61 185.42 0)
			(effects
				(font
					(size 1.27 1.27)
					(thickness 0.15)
				)
				(justify left bottom)
				(hide yes)
			)
		)
		(property "Val" "0R"
			(at 287.02 163.83 0)
			(effects
				(font
					(size 1.27 1.27)
					(thickness 0.15)
				)
			)
		)
		(property "License" "Apache-2.0"
			(at 308.61 190.5 0)
			(effects
				(font
					(size 1.27 1.27)
					(thickness 0.15)
				)
				(justify left bottom)
				(hide yes)
			)
		)
		(property "Author" "Antmicro"
			(at 308.61 193.04 0)
			(effects
				(font
					(size 1.27 1.27)
					(thickness 0.15)
				)
				(justify left bottom)
				(hide yes)
			)
		)
		(property "Tolerance" "~"
			(at 308.61 175.26 0)
			(effects
				(font
					(size 1.27 1.27)
				)
				(justify left bottom)
				(hide yes)
			)
		)
		(property "Current" "1A"
			(at 290.83 173.99 0)
			(effects
				(font
					(size 1.27 1.27)
					(thickness 0.15)
				)
				(hide yes)
			)
		)
		(pin "1"
		)
		(pin "2"
		)
		(instances
			(project "data-center-rdimm-ddr5-tester"
				(path ""
					(reference "R88")
					(unit 1)
				)
			)
		)
	)
	(symbol
		(lib_id "antmicroResistors0402:R_5k11_0402")
		(at 67.31 46.99 0)
		(mirror x)
		(unit 1)
		(exclude_from_sim no)
		(in_bom yes)
		(on_board yes)
		(dnp no)
		(property "Reference" "R69"
			(at 74.295 45.72 0)
			(effects
				(font
					(size 1.27 1.27)
				)
			)
		)
		(property "Value" "R_5k11_0402"
			(at 87.63 34.29 0)
			(effects
				(font
					(size 1.27 1.27)
					(thickness 0.15)
				)
				(justify left bottom)
				(hide yes)
			)
		)
		(property "Footprint" "antmicro-footprints:R_0402_1005Metric"
			(at 87.63 31.75 0)
			(effects
				(font
					(size 1.27 1.27)
					(thickness 0.15)
				)
				(justify left bottom)
				(hide yes)
			)
		)
		(property "Datasheet" "https://www.bourns.com/docs/product-datasheets/cr.pdf"
			(at 87.63 29.21 0)
			(effects
				(font
					(size 1.27 1.27)
					(thickness 0.15)
				)
				(justify left bottom)
				(hide yes)
			)
		)
		(property "Description" ""
			(at 67.31 46.99 0)
			(effects
				(font
					(size 1.27 1.27)
				)
				(hide yes)
			)
		)
		(property "Manufacturer" "Bourns"
			(at 87.63 24.13 0)
			(effects
				(font
					(size 1.27 1.27)
					(thickness 0.15)
				)
				(justify left bottom)
				(hide yes)
			)
		)
		(property "MPN" "CR0402-FX-5111GLF"
			(at 87.63 26.67 0)
			(effects
				(font
					(size 1.27 1.27)
					(thickness 0.15)
				)
				(justify left bottom)
				(hide yes)
			)
		)
		(property "Val" "5k11"
			(at 69.85 48.895 0)
			(effects
				(font
					(size 1.27 1.27)
					(thickness 0.15)
				)
			)
		)
		(property "License" "Apache-2.0"
			(at 87.63 21.59 0)
			(effects
				(font
					(size 1.27 1.27)
					(thickness 0.15)
				)
				(justify left bottom)
				(hide yes)
			)
		)
		(property "Author" "Antmicro"
			(at 87.63 19.05 0)
			(effects
				(font
					(size 1.27 1.27)
					(thickness 0.15)
				)
				(justify left bottom)
				(hide yes)
			)
		)
		(property "Tolerance" "1%"
			(at 87.63 36.83 0)
			(effects
				(font
					(size 1.27 1.27)
				)
				(justify left bottom)
				(hide yes)
			)
		)
		(pin "1"
		)
		(pin "2"
		)
		(instances
			(project "data-center-rdimm-ddr5-tester"
				(path ""
					(reference "R69")
					(unit 1)
				)
			)
		)
	)
	(symbol
		(lib_id "antmicropower:+3V3")
		(at 278.13 198.12 0)
		(unit 1)
		(exclude_from_sim no)
		(in_bom yes)
		(on_board yes)
		(dnp no)
		(property "Reference" "#PWR010"
			(at 278.13 201.93 0)
			(effects
				(font
					(size 1.27 1.27)
				)
				(hide yes)
			)
		)
		(property "Value" "+3V3"
			(at 274.955 195.58 0)
			(effects
				(font
					(size 1.27 1.27)
					(thickness 0.15)
				)
				(justify left bottom)
			)
		)
		(property "Footprint" ""
			(at 293.37 205.74 0)
			(effects
				(font
					(size 1.27 1.27)
					(thickness 0.15)
				)
				(justify left bottom)
				(hide yes)
			)
		)
		(property "Datasheet" ""
			(at 293.37 208.28 0)
			(effects
				(font
					(size 1.27 1.27)
					(thickness 0.15)
				)
				(justify left bottom)
				(hide yes)
			)
		)
		(property "Description" ""
			(at 278.13 198.12 0)
			(effects
				(font
					(size 1.27 1.27)
				)
				(hide yes)
			)
		)
		(property "Author" "Antmicro"
			(at 293.37 200.66 0)
			(effects
				(font
					(size 1.27 1.27)
					(thickness 0.15)
				)
				(justify left bottom)
				(hide yes)
			)
		)
		(property "License" "Apache-2.0"
			(at 293.37 203.2 0)
			(effects
				(font
					(size 1.27 1.27)
					(thickness 0.15)
				)
				(justify left bottom)
				(hide yes)
			)
		)
		(pin "1"
		)
		(instances
			(project "data-center-rdimm-ddr5-tester"
				(path ""
					(reference "#PWR010")
					(unit 1)
				)
			)
		)
	)
	(symbol
		(lib_id "antmicroCapacitors0402:C_100n_0402")
		(at 384.81 224.79 90)
		(unit 1)
		(exclude_from_sim no)
		(in_bom yes)
		(on_board yes)
		(dnp no)
		(fields_autoplaced yes)
		(property "Reference" "C238"
			(at 387.1341 221.413 90)
			(effects
				(font
					(size 1.27 1.27)
					(thickness 0.15)
				)
				(justify right)
			)
		)
		(property "Value" "C_100n_0402"
			(at 394.97 204.47 0)
			(effects
				(font
					(size 1.27 1.27)
					(thickness 0.15)
				)
				(justify left bottom)
				(hide yes)
			)
		)
		(property "Footprint" "antmicro-footprints:C_0402_1005Metric"
			(at 397.51 204.47 0)
			(effects
				(font
					(size 1.27 1.27)
					(thickness 0.15)
				)
				(justify left bottom)
				(hide yes)
			)
		)
		(property "Datasheet" "https://www.murata.com/products/productdetail?partno=GRM155R61H104KE14%23"
			(at 400.05 204.47 0)
			(effects
				(font
					(size 1.27 1.27)
					(thickness 0.15)
				)
				(justify left bottom)
				(hide yes)
			)
		)
		(property "Description" ""
			(at 384.81 224.79 0)
			(effects
				(font
					(size 1.27 1.27)
				)
				(hide yes)
			)
		)
		(property "MPN" "GRM155R61H104KE14D"
			(at 402.59 204.47 0)
			(effects
				(font
					(size 1.27 1.27)
					(thickness 0.15)
				)
				(justify left bottom)
				(hide yes)
			)
		)
		(property "Manufacturer" "Murata"
			(at 405.13 204.47 0)
			(effects
				(font
					(size 1.27 1.27)
					(thickness 0.15)
				)
				(justify left bottom)
				(hide yes)
			)
		)
		(property "License" "Apache-2.0"
			(at 407.67 204.47 0)
			(effects
				(font
					(size 1.27 1.27)
					(thickness 0.15)
				)
				(justify left bottom)
				(hide yes)
			)
		)
		(property "Author" "Antmicro"
			(at 410.21 204.47 0)
			(effects
				(font
					(size 1.27 1.27)
					(thickness 0.15)
				)
				(justify left bottom)
				(hide yes)
			)
		)
		(property "Val" "100n"
			(at 387.1341 223.9367 90)
			(effects
				(font
					(size 1.27 1.27)
					(thickness 0.15)
				)
				(justify right)
			)
		)
		(property "Voltage" "50V"
			(at 412.75 204.47 0)
			(effects
				(font
					(size 1.27 1.27)
				)
				(justify left bottom)
				(hide yes)
			)
		)
		(property "Dielectric" "X5R"
			(at 415.29 204.47 0)
			(effects
				(font
					(size 1.27 1.27)
				)
				(justify left bottom)
				(hide yes)
			)
		)
		(pin "1"
		)
		(pin "2"
		)
		(instances
			(project "data-center-rdimm-ddr5-tester"
				(path ""
					(reference "C238")
					(unit 1)
				)
			)
		)
	)
	(symbol
		(lib_id "antmicropower:GND")
		(at 372.11 207.01 0)
		(unit 1)
		(exclude_from_sim no)
		(in_bom yes)
		(on_board yes)
		(dnp no)
		(property "Reference" "#PWR012"
			(at 372.11 213.36 0)
			(effects
				(font
					(size 1.27 1.27)
				)
				(hide yes)
			)
		)
		(property "Value" "GND"
			(at 370.205 211.455 0)
			(effects
				(font
					(size 1.27 1.27)
					(thickness 0.15)
				)
				(justify left bottom)
			)
		)
		(property "Footprint" ""
			(at 381 214.63 0)
			(effects
				(font
					(size 1.27 1.27)
					(thickness 0.15)
				)
				(justify left bottom)
				(hide yes)
			)
		)
		(property "Datasheet" ""
			(at 381 219.71 0)
			(effects
				(font
					(size 1.27 1.27)
					(thickness 0.15)
				)
				(justify left bottom)
				(hide yes)
			)
		)
		(property "Description" ""
			(at 372.11 207.01 0)
			(effects
				(font
					(size 1.27 1.27)
				)
				(hide yes)
			)
		)
		(property "Author" "Antmicro"
			(at 381 212.09 0)
			(effects
				(font
					(size 1.27 1.27)
					(thickness 0.15)
				)
				(justify left bottom)
				(hide yes)
			)
		)
		(property "License" "Apache-2.0"
			(at 381 214.63 0)
			(effects
				(font
					(size 1.27 1.27)
					(thickness 0.15)
				)
				(justify left bottom)
				(hide yes)
			)
		)
		(pin "1"
		)
		(instances
			(project "data-center-rdimm-ddr5-tester"
				(path ""
					(reference "#PWR012")
					(unit 1)
				)
			)
		)
	)
	(symbol
		(lib_id "antmicropower:GND")
		(at 256.54 181.61 0)
		(unit 1)
		(exclude_from_sim no)
		(in_bom yes)
		(on_board yes)
		(dnp no)
		(property "Reference" "#PWR0206"
			(at 256.54 187.96 0)
			(effects
				(font
					(size 1.27 1.27)
				)
				(hide yes)
			)
		)
		(property "Value" "GND"
			(at 254.635 186.055 0)
			(effects
				(font
					(size 1.27 1.27)
					(thickness 0.15)
				)
				(justify left bottom)
			)
		)
		(property "Footprint" ""
			(at 265.43 189.23 0)
			(effects
				(font
					(size 1.27 1.27)
					(thickness 0.15)
				)
				(justify left bottom)
				(hide yes)
			)
		)
		(property "Datasheet" ""
			(at 265.43 194.31 0)
			(effects
				(font
					(size 1.27 1.27)
					(thickness 0.15)
				)
				(justify left bottom)
				(hide yes)
			)
		)
		(property "Description" ""
			(at 256.54 181.61 0)
			(effects
				(font
					(size 1.27 1.27)
				)
				(hide yes)
			)
		)
		(property "Author" "Antmicro"
			(at 265.43 186.69 0)
			(effects
				(font
					(size 1.27 1.27)
					(thickness 0.15)
				)
				(justify left bottom)
				(hide yes)
			)
		)
		(property "License" "Apache-2.0"
			(at 265.43 189.23 0)
			(effects
				(font
					(size 1.27 1.27)
					(thickness 0.15)
				)
				(justify left bottom)
				(hide yes)
			)
		)
		(pin "1"
		)
		(instances
			(project "data-center-rdimm-ddr5-tester"
				(path ""
					(reference "#PWR0206")
					(unit 1)
				)
			)
		)
	)
	(symbol
		(lib_id "antmicroResistors0402:R_22R_0402")
		(at 173.99 154.94 0)
		(unit 1)
		(exclude_from_sim no)
		(in_bom no)
		(on_board yes)
		(dnp yes)
		(property "Reference" "R59"
			(at 180.975 153.67 0)
			(effects
				(font
					(size 1.27 1.27)
				)
			)
		)
		(property "Value" "R_22R_0402"
			(at 194.31 167.64 0)
			(effects
				(font
					(size 1.27 1.27)
					(thickness 0.15)
				)
				(justify left bottom)
				(hide yes)
			)
		)
		(property "Footprint" "antmicro-footprints:R_0402_1005Metric"
			(at 194.31 170.18 0)
			(effects
				(font
					(size 1.27 1.27)
					(thickness 0.15)
				)
				(justify left bottom)
				(hide yes)
			)
		)
		(property "Datasheet" "https://www.bourns.com/docs/product-datasheets/cr.pdf"
			(at 194.31 172.72 0)
			(effects
				(font
					(size 1.27 1.27)
					(thickness 0.15)
				)
				(justify left bottom)
				(hide yes)
			)
		)
		(property "Description" ""
			(at 173.99 154.94 0)
			(effects
				(font
					(size 1.27 1.27)
				)
				(hide yes)
			)
		)
		(property "Manufacturer" "Bourns"
			(at 194.31 177.8 0)
			(effects
				(font
					(size 1.27 1.27)
					(thickness 0.15)
				)
				(justify left bottom)
				(hide yes)
			)
		)
		(property "MPN" "CR0402-FX-22R0GLF"
			(at 194.31 175.26 0)
			(effects
				(font
					(size 1.27 1.27)
					(thickness 0.15)
				)
				(justify left bottom)
				(hide yes)
			)
		)
		(property "Val" "22R"
			(at 172.085 153.67 0)
			(effects
				(font
					(size 1.27 1.27)
					(thickness 0.15)
				)
			)
		)
		(property "License" "Apache-2.0"
			(at 194.31 180.34 0)
			(effects
				(font
					(size 1.27 1.27)
					(thickness 0.15)
				)
				(justify left bottom)
				(hide yes)
			)
		)
		(property "Author" "Antmicro"
			(at 194.31 182.88 0)
			(effects
				(font
					(size 1.27 1.27)
					(thickness 0.15)
				)
				(justify left bottom)
				(hide yes)
			)
		)
		(property "Tolerance" "1%"
			(at 194.31 165.1 0)
			(effects
				(font
					(size 1.27 1.27)
				)
				(justify left bottom)
				(hide yes)
			)
		)
		(pin "1"
		)
		(pin "2"
		)
		(instances
			(project "data-center-rdimm-ddr5-tester"
				(path ""
					(reference "R59")
					(unit 1)
				)
			)
		)
	)
	(symbol
		(lib_id "antmicropower:PWR_FLAG")
		(at 64.77 125.73 0)
		(unit 1)
		(exclude_from_sim no)
		(in_bom yes)
		(on_board yes)
		(dnp no)
		(fields_autoplaced yes)
		(property "Reference" "#FLG0103"
			(at 64.77 123.825 0)
			(effects
				(font
					(size 1.27 1.27)
				)
				(hide yes)
			)
		)
		(property "Value" "PWR_FLAG"
			(at 64.77 122.1542 0)
			(effects
				(font
					(size 1.27 1.27)
				)
			)
		)
		(property "Footprint" ""
			(at 64.77 125.73 0)
			(effects
				(font
					(size 1.27 1.27)
				)
				(hide yes)
			)
		)
		(property "Datasheet" ""
			(at 64.77 125.73 0)
			(effects
				(font
					(size 1.27 1.27)
				)
				(hide yes)
			)
		)
		(property "Description" ""
			(at 64.77 125.73 0)
			(effects
				(font
					(size 1.27 1.27)
				)
				(hide yes)
			)
		)
		(pin "1"
		)
		(instances
			(project "data-center-rdimm-ddr5-tester"
				(path ""
					(reference "#FLG0103")
					(unit 1)
				)
			)
		)
	)
	(symbol
		(lib_id "antmicropower:+3V3_AON")
		(at 383.54 158.75 0)
		(mirror y)
		(unit 1)
		(exclude_from_sim no)
		(in_bom yes)
		(on_board yes)
		(dnp no)
		(property "Reference" "#PWR0194"
			(at 383.54 162.56 0)
			(effects
				(font
					(size 1.27 1.27)
				)
				(hide yes)
			)
		)
		(property "Value" "+3V3_AON"
			(at 389.255 155.575 0)
			(effects
				(font
					(size 1.27 1.27)
				)
			)
		)
		(property "Footprint" ""
			(at 383.54 158.75 0)
			(effects
				(font
					(size 1.27 1.27)
				)
				(hide yes)
			)
		)
		(property "Datasheet" ""
			(at 383.54 158.75 0)
			(effects
				(font
					(size 1.27 1.27)
				)
				(hide yes)
			)
		)
		(property "Description" ""
			(at 383.54 158.75 0)
			(effects
				(font
					(size 1.27 1.27)
				)
				(hide yes)
			)
		)
		(pin "1"
		)
		(instances
			(project "data-center-rdimm-ddr5-tester"
				(path ""
					(reference "#PWR0194")
					(unit 1)
				)
			)
		)
	)
	(symbol
		(lib_id "antmicroCoaxialConnectorsRF:U_FL-R-SMT-1")
		(at 372.11 76.2 0)
		(mirror y)
		(unit 1)
		(exclude_from_sim no)
		(in_bom yes)
		(on_board yes)
		(dnp no)
		(fields_autoplaced yes)
		(property "Reference" "J15"
			(at 366.1238 69.215 0)
			(effects
				(font
					(size 1.27 1.27)
					(thickness 0.15)
				)
			)
		)
		(property "Value" "U_FL-R-SMT-1"
			(at 351.79 83.82 0)
			(effects
				(font
					(size 1.27 1.27)
					(thickness 0.15)
				)
				(justify left bottom)
				(hide yes)
			)
		)
		(property "Footprint" "antmicro-footprints:Coax_Conn_U.FL"
			(at 351.79 86.36 0)
			(effects
				(font
					(size 1.27 1.27)
					(thickness 0.15)
				)
				(justify left bottom)
				(hide yes)
			)
		)
		(property "Datasheet" "https://media.digikey.com/pdf/Data%20Sheets/Hirose%20PDFs/UFL%20Series.pdf"
			(at 351.79 88.9 0)
			(effects
				(font
					(size 1.27 1.27)
					(thickness 0.15)
				)
				(justify left bottom)
				(hide yes)
			)
		)
		(property "Description" ""
			(at 372.11 76.2 0)
			(effects
				(font
					(size 1.27 1.27)
				)
				(hide yes)
			)
		)
		(property "MPN" "U.FL-R-SMT-1(10)"
			(at 366.1238 71.755 0)
			(effects
				(font
					(size 1.27 1.27)
					(thickness 0.15)
				)
			)
		)
		(property "Manufacturer" "Hirose Electric"
			(at 351.79 91.44 0)
			(effects
				(font
					(size 1.27 1.27)
					(thickness 0.15)
				)
				(justify left bottom)
				(hide yes)
			)
		)
		(property "Author" "Antmicro"
			(at 351.79 93.98 0)
			(effects
				(font
					(size 1.27 1.27)
					(thickness 0.15)
				)
				(justify left bottom)
				(hide yes)
			)
		)
		(property "License" "Apache-2.0"
			(at 351.79 96.52 0)
			(effects
				(font
					(size 1.27 1.27)
					(thickness 0.15)
				)
				(justify left bottom)
				(hide yes)
			)
		)
		(pin "SH2"
		)
		(pin "SH1"
		)
		(pin "1"
		)
		(instances
			(project "data-center-rdimm-ddr5-tester"
				(path ""
					(reference "J15")
					(unit 1)
				)
			)
		)
	)
	(symbol
		(lib_id "antmicroCapacitors0402:C_100n_0402")
		(at 373.38 140.97 90)
		(unit 1)
		(exclude_from_sim no)
		(in_bom yes)
		(on_board yes)
		(dnp no)
		(fields_autoplaced yes)
		(property "Reference" "C121"
			(at 375.7041 137.593 90)
			(effects
				(font
					(size 1.27 1.27)
					(thickness 0.15)
				)
				(justify right)
			)
		)
		(property "Value" "C_100n_0402"
			(at 383.54 120.65 0)
			(effects
				(font
					(size 1.27 1.27)
					(thickness 0.15)
				)
				(justify left bottom)
				(hide yes)
			)
		)
		(property "Footprint" "antmicro-footprints:C_0402_1005Metric"
			(at 386.08 120.65 0)
			(effects
				(font
					(size 1.27 1.27)
					(thickness 0.15)
				)
				(justify left bottom)
				(hide yes)
			)
		)
		(property "Datasheet" "https://www.murata.com/products/productdetail?partno=GRM155R61H104KE14%23"
			(at 388.62 120.65 0)
			(effects
				(font
					(size 1.27 1.27)
					(thickness 0.15)
				)
				(justify left bottom)
				(hide yes)
			)
		)
		(property "Description" ""
			(at 373.38 140.97 0)
			(effects
				(font
					(size 1.27 1.27)
				)
				(hide yes)
			)
		)
		(property "MPN" "GRM155R61H104KE14D"
			(at 391.16 120.65 0)
			(effects
				(font
					(size 1.27 1.27)
					(thickness 0.15)
				)
				(justify left bottom)
				(hide yes)
			)
		)
		(property "Manufacturer" "Murata"
			(at 393.7 120.65 0)
			(effects
				(font
					(size 1.27 1.27)
					(thickness 0.15)
				)
				(justify left bottom)
				(hide yes)
			)
		)
		(property "License" "Apache-2.0"
			(at 396.24 120.65 0)
			(effects
				(font
					(size 1.27 1.27)
					(thickness 0.15)
				)
				(justify left bottom)
				(hide yes)
			)
		)
		(property "Author" "Antmicro"
			(at 398.78 120.65 0)
			(effects
				(font
					(size 1.27 1.27)
					(thickness 0.15)
				)
				(justify left bottom)
				(hide yes)
			)
		)
		(property "Val" "100n"
			(at 375.7041 140.1167 90)
			(effects
				(font
					(size 1.27 1.27)
					(thickness 0.15)
				)
				(justify right)
			)
		)
		(property "Voltage" "50V"
			(at 401.32 120.65 0)
			(effects
				(font
					(size 1.27 1.27)
				)
				(justify left bottom)
				(hide yes)
			)
		)
		(property "Dielectric" "X5R"
			(at 403.86 120.65 0)
			(effects
				(font
					(size 1.27 1.27)
				)
				(justify left bottom)
				(hide yes)
			)
		)
		(pin "1"
		)
		(pin "2"
		)
		(instances
			(project "data-center-rdimm-ddr5-tester"
				(path ""
					(reference "C121")
					(unit 1)
				)
			)
		)
	)
	(symbol
		(lib_id "antmicroLEDIndicationDiscrete:LED_G_0603_KP-1608CGCK")
		(at 116.84 259.08 0)
		(unit 1)
		(exclude_from_sim no)
		(in_bom yes)
		(on_board yes)
		(dnp no)
		(property "Reference" "D11"
			(at 123.825 257.81 0)
			(effects
				(font
					(size 1.27 1.27)
					(thickness 0.15)
				)
			)
		)
		(property "Value" "LED_G_0603_KP-1608CGCK"
			(at 139.7 266.7 0)
			(effects
				(font
					(size 1.27 1.27)
					(thickness 0.15)
				)
				(justify left bottom)
				(hide yes)
			)
		)
		(property "Footprint" "antmicro-footprints:LED_0603_1608Metric_G"
			(at 139.7 269.24 0)
			(effects
				(font
					(size 1.27 1.27)
					(thickness 0.15)
				)
				(justify left bottom)
				(hide yes)
			)
		)
		(property "Datasheet" "http://www.kingbright.com/attachments/file/psearch//000/00/00/KP-1608CGCK(Ver.23B).pdf"
			(at 139.7 271.78 0)
			(effects
				(font
					(size 1.27 1.27)
					(thickness 0.15)
				)
				(justify left bottom)
				(hide yes)
			)
		)
		(property "Description" ""
			(at 116.84 259.08 0)
			(effects
				(font
					(size 1.27 1.27)
				)
				(hide yes)
			)
		)
		(property "MPN" "KP-1608CGCK"
			(at 119.38 255.27 0)
			(effects
				(font
					(size 1.27 1.27)
					(thickness 0.15)
				)
			)
		)
		(property "Manufacturer" "Kingbright"
			(at 139.7 276.86 0)
			(effects
				(font
					(size 1.27 1.27)
					(thickness 0.15)
				)
				(justify left bottom)
				(hide yes)
			)
		)
		(property "Color" "Green"
			(at 114.935 257.81 0)
			(effects
				(font
					(size 1.27 1.27)
				)
			)
		)
		(property "Author" "Antmicro"
			(at 139.7 279.4 0)
			(effects
				(font
					(size 1.27 1.27)
					(thickness 0.15)
				)
				(justify left bottom)
				(hide yes)
			)
		)
		(property "License" "Apache-2.0"
			(at 139.7 281.94 0)
			(effects
				(font
					(size 1.27 1.27)
					(thickness 0.15)
				)
				(justify left bottom)
				(hide yes)
			)
		)
		(pin "1"
		)
		(pin "2"
		)
		(instances
			(project "data-center-rdimm-ddr5-tester"
				(path ""
					(reference "D11")
					(unit 1)
				)
			)
		)
	)
	(symbol
		(lib_id "antmicropower:GND")
		(at 373.38 142.24 0)
		(unit 1)
		(exclude_from_sim no)
		(in_bom yes)
		(on_board yes)
		(dnp no)
		(property "Reference" "#PWR0196"
			(at 373.38 148.59 0)
			(effects
				(font
					(size 1.27 1.27)
				)
				(hide yes)
			)
		)
		(property "Value" "GND"
			(at 371.475 146.685 0)
			(effects
				(font
					(size 1.27 1.27)
					(thickness 0.15)
				)
				(justify left bottom)
			)
		)
		(property "Footprint" ""
			(at 382.27 149.86 0)
			(effects
				(font
					(size 1.27 1.27)
					(thickness 0.15)
				)
				(justify left bottom)
				(hide yes)
			)
		)
		(property "Datasheet" ""
			(at 382.27 154.94 0)
			(effects
				(font
					(size 1.27 1.27)
					(thickness 0.15)
				)
				(justify left bottom)
				(hide yes)
			)
		)
		(property "Description" ""
			(at 373.38 142.24 0)
			(effects
				(font
					(size 1.27 1.27)
				)
				(hide yes)
			)
		)
		(property "Author" "Antmicro"
			(at 382.27 147.32 0)
			(effects
				(font
					(size 1.27 1.27)
					(thickness 0.15)
				)
				(justify left bottom)
				(hide yes)
			)
		)
		(property "License" "Apache-2.0"
			(at 382.27 149.86 0)
			(effects
				(font
					(size 1.27 1.27)
					(thickness 0.15)
				)
				(justify left bottom)
				(hide yes)
			)
		)
		(pin "1"
		)
		(instances
			(project "data-center-rdimm-ddr5-tester"
				(path ""
					(reference "#PWR0196")
					(unit 1)
				)
			)
		)
	)
	(symbol
		(lib_id "antmicropower:GND")
		(at 328.93 49.53 0)
		(unit 1)
		(exclude_from_sim no)
		(in_bom yes)
		(on_board yes)
		(dnp no)
		(fields_autoplaced yes)
		(property "Reference" "#PWR0513"
			(at 328.93 55.88 0)
			(effects
				(font
					(size 1.27 1.27)
				)
				(hide yes)
			)
		)
		(property "Value" "GND"
			(at 327.025 53.975 0)
			(effects
				(font
					(size 1.27 1.27)
					(thickness 0.15)
				)
				(justify left bottom)
			)
		)
		(property "Footprint" ""
			(at 337.82 57.15 0)
			(effects
				(font
					(size 1.27 1.27)
					(thickness 0.15)
				)
				(justify left bottom)
				(hide yes)
			)
		)
		(property "Datasheet" ""
			(at 337.82 62.23 0)
			(effects
				(font
					(size 1.27 1.27)
					(thickness 0.15)
				)
				(justify left bottom)
				(hide yes)
			)
		)
		(property "Description" ""
			(at 328.93 49.53 0)
			(effects
				(font
					(size 1.27 1.27)
				)
				(hide yes)
			)
		)
		(property "Author" "Antmicro"
			(at 337.82 54.61 0)
			(effects
				(font
					(size 1.27 1.27)
					(thickness 0.15)
				)
				(justify left bottom)
				(hide yes)
			)
		)
		(property "License" "Apache-2.0"
			(at 337.82 57.15 0)
			(effects
				(font
					(size 1.27 1.27)
					(thickness 0.15)
				)
				(justify left bottom)
				(hide yes)
			)
		)
		(pin "1"
		)
		(instances
			(project "data-center-rdimm-ddr5-tester"
				(path ""
					(reference "#PWR0513")
					(unit 1)
				)
			)
		)
	)
	(symbol
		(lib_id "antmicropower:GND")
		(at 52.07 156.21 0)
		(unit 1)
		(exclude_from_sim no)
		(in_bom yes)
		(on_board yes)
		(dnp no)
		(fields_autoplaced yes)
		(property "Reference" "#PWR0257"
			(at 52.07 162.56 0)
			(effects
				(font
					(size 1.27 1.27)
				)
				(hide yes)
			)
		)
		(property "Value" "GND"
			(at 50.165 160.655 0)
			(effects
				(font
					(size 1.27 1.27)
					(thickness 0.15)
				)
				(justify left bottom)
			)
		)
		(property "Footprint" ""
			(at 60.96 163.83 0)
			(effects
				(font
					(size 1.27 1.27)
					(thickness 0.15)
				)
				(justify left bottom)
				(hide yes)
			)
		)
		(property "Datasheet" ""
			(at 60.96 168.91 0)
			(effects
				(font
					(size 1.27 1.27)
					(thickness 0.15)
				)
				(justify left bottom)
				(hide yes)
			)
		)
		(property "Description" ""
			(at 52.07 156.21 0)
			(effects
				(font
					(size 1.27 1.27)
				)
				(hide yes)
			)
		)
		(property "Author" "Antmicro"
			(at 60.96 161.29 0)
			(effects
				(font
					(size 1.27 1.27)
					(thickness 0.15)
				)
				(justify left bottom)
				(hide yes)
			)
		)
		(property "License" "Apache-2.0"
			(at 60.96 163.83 0)
			(effects
				(font
					(size 1.27 1.27)
					(thickness 0.15)
				)
				(justify left bottom)
				(hide yes)
			)
		)
		(pin "1"
		)
		(instances
			(project "data-center-rdimm-ddr5-tester"
				(path ""
					(reference "#PWR0257")
					(unit 1)
				)
			)
		)
	)
	(symbol
		(lib_id "antmicroCoaxialConnectorsRF:U_FL-R-SMT-1")
		(at 384.81 76.2 0)
		(unit 1)
		(exclude_from_sim no)
		(in_bom yes)
		(on_board yes)
		(dnp no)
		(property "Reference" "J16"
			(at 389.255 69.215 0)
			(effects
				(font
					(size 1.27 1.27)
					(thickness 0.15)
				)
				(justify left)
			)
		)
		(property "Value" "U_FL-R-SMT-1"
			(at 405.13 83.82 0)
			(effects
				(font
					(size 1.27 1.27)
					(thickness 0.15)
				)
				(justify left bottom)
				(hide yes)
			)
		)
		(property "Footprint" "antmicro-footprints:Coax_Conn_U.FL"
			(at 405.13 86.36 0)
			(effects
				(font
					(size 1.27 1.27)
					(thickness 0.15)
				)
				(justify left bottom)
				(hide yes)
			)
		)
		(property "Datasheet" "https://media.digikey.com/pdf/Data%20Sheets/Hirose%20PDFs/UFL%20Series.pdf"
			(at 405.13 88.9 0)
			(effects
				(font
					(size 1.27 1.27)
					(thickness 0.15)
				)
				(justify left bottom)
				(hide yes)
			)
		)
		(property "Description" ""
			(at 384.81 76.2 0)
			(effects
				(font
					(size 1.27 1.27)
				)
				(hide yes)
			)
		)
		(property "MPN" "U.FL-R-SMT-1(10)"
			(at 381.635 71.755 0)
			(effects
				(font
					(size 1.27 1.27)
					(thickness 0.15)
				)
				(justify left)
			)
		)
		(property "Manufacturer" "Hirose Electric"
			(at 405.13 91.44 0)
			(effects
				(font
					(size 1.27 1.27)
					(thickness 0.15)
				)
				(justify left bottom)
				(hide yes)
			)
		)
		(property "Author" "Antmicro"
			(at 405.13 93.98 0)
			(effects
				(font
					(size 1.27 1.27)
					(thickness 0.15)
				)
				(justify left bottom)
				(hide yes)
			)
		)
		(property "License" "Apache-2.0"
			(at 405.13 96.52 0)
			(effects
				(font
					(size 1.27 1.27)
					(thickness 0.15)
				)
				(justify left bottom)
				(hide yes)
			)
		)
		(pin "SH2"
		)
		(pin "SH1"
		)
		(pin "1"
		)
		(instances
			(project "data-center-rdimm-ddr5-tester"
				(path ""
					(reference "J16")
					(unit 1)
				)
			)
		)
	)
	(symbol
		(lib_name "BAT54-02V-G3-08_1")
		(lib_id "antmicroDiodesRectifiersSingle:BAT54-02V-G3-08")
		(at 289.56 175.26 0)
		(unit 1)
		(exclude_from_sim no)
		(in_bom yes)
		(on_board yes)
		(dnp no)
		(property "Reference" "D15"
			(at 296.545 173.99 0)
			(effects
				(font
					(size 1.27 1.27)
					(thickness 0.15)
				)
			)
		)
		(property "Value" "BAT54-02V-G3-08"
			(at 311.15 190.5 0)
			(effects
				(font
					(size 1.27 1.27)
					(thickness 0.15)
				)
				(justify left bottom)
				(hide yes)
			)
		)
		(property "Footprint" "antmicro-footprints:SOD-523"
			(at 311.15 185.42 0)
			(effects
				(font
					(size 1.27 1.27)
					(thickness 0.15)
				)
				(justify left bottom)
				(hide yes)
			)
		)
		(property "Datasheet" "https://www.vishay.com/docs/85633/bat5402v.pdf"
			(at 311.15 187.96 0)
			(effects
				(font
					(size 1.27 1.27)
					(thickness 0.15)
				)
				(justify left bottom)
				(hide yes)
			)
		)
		(property "Description" ""
			(at 289.56 175.26 0)
			(effects
				(font
					(size 1.27 1.27)
				)
				(hide yes)
			)
		)
		(property "MPN" "BAT54-02V-G3-08"
			(at 293.37 180.34 0)
			(effects
				(font
					(size 1.27 1.27)
					(thickness 0.15)
				)
			)
		)
		(property "Manufacturer" "Vishay"
			(at 311.15 193.04 0)
			(effects
				(font
					(size 1.27 1.27)
					(thickness 0.15)
				)
				(justify left bottom)
				(hide yes)
			)
		)
		(property "Author" "Antmicro"
			(at 311.15 195.58 0)
			(effects
				(font
					(size 1.27 1.27)
					(thickness 0.15)
				)
				(justify left bottom)
				(hide yes)
			)
		)
		(property "License" "Apache-2.0"
			(at 311.15 198.12 0)
			(effects
				(font
					(size 1.27 1.27)
					(thickness 0.15)
				)
				(justify left bottom)
				(hide yes)
			)
		)
		(pin "1"
		)
		(pin "2"
		)
		(instances
			(project "data-center-rdimm-ddr5-tester"
				(path ""
					(reference "D15")
					(unit 1)
				)
			)
		)
	)
	(symbol
		(lib_id "antmicroCapacitors0402:C_100n_0402")
		(at 200.66 251.46 90)
		(unit 1)
		(exclude_from_sim no)
		(in_bom yes)
		(on_board yes)
		(dnp no)
		(fields_autoplaced yes)
		(property "Reference" "C128"
			(at 202.9841 248.083 90)
			(effects
				(font
					(size 1.27 1.27)
					(thickness 0.15)
				)
				(justify right)
			)
		)
		(property "Value" "C_100n_0402"
			(at 210.82 231.14 0)
			(effects
				(font
					(size 1.27 1.27)
					(thickness 0.15)
				)
				(justify left bottom)
				(hide yes)
			)
		)
		(property "Footprint" "antmicro-footprints:C_0402_1005Metric"
			(at 213.36 231.14 0)
			(effects
				(font
					(size 1.27 1.27)
					(thickness 0.15)
				)
				(justify left bottom)
				(hide yes)
			)
		)
		(property "Datasheet" "https://www.murata.com/products/productdetail?partno=GRM155R61H104KE14%23"
			(at 215.9 231.14 0)
			(effects
				(font
					(size 1.27 1.27)
					(thickness 0.15)
				)
				(justify left bottom)
				(hide yes)
			)
		)
		(property "Description" ""
			(at 200.66 251.46 0)
			(effects
				(font
					(size 1.27 1.27)
				)
				(hide yes)
			)
		)
		(property "MPN" "GRM155R61H104KE14D"
			(at 218.44 231.14 0)
			(effects
				(font
					(size 1.27 1.27)
					(thickness 0.15)
				)
				(justify left bottom)
				(hide yes)
			)
		)
		(property "Manufacturer" "Murata"
			(at 220.98 231.14 0)
			(effects
				(font
					(size 1.27 1.27)
					(thickness 0.15)
				)
				(justify left bottom)
				(hide yes)
			)
		)
		(property "License" "Apache-2.0"
			(at 223.52 231.14 0)
			(effects
				(font
					(size 1.27 1.27)
					(thickness 0.15)
				)
				(justify left bottom)
				(hide yes)
			)
		)
		(property "Author" "Antmicro"
			(at 226.06 231.14 0)
			(effects
				(font
					(size 1.27 1.27)
					(thickness 0.15)
				)
				(justify left bottom)
				(hide yes)
			)
		)
		(property "Val" "100n"
			(at 202.9841 250.6067 90)
			(effects
				(font
					(size 1.27 1.27)
					(thickness 0.15)
				)
				(justify right)
			)
		)
		(property "Voltage" "50V"
			(at 228.6 231.14 0)
			(effects
				(font
					(size 1.27 1.27)
				)
				(justify left bottom)
				(hide yes)
			)
		)
		(property "Dielectric" "X5R"
			(at 231.14 231.14 0)
			(effects
				(font
					(size 1.27 1.27)
				)
				(justify left bottom)
				(hide yes)
			)
		)
		(pin "1"
		)
		(pin "2"
		)
		(instances
			(project "data-center-rdimm-ddr5-tester"
				(path ""
					(reference "C128")
					(unit 1)
				)
			)
		)
	)
	(symbol
		(lib_id "antmicroResonators:Resonator_12MHz_ABM8G")
		(at 83.82 189.23 0)
		(unit 1)
		(exclude_from_sim no)
		(in_bom yes)
		(on_board yes)
		(dnp no)
		(fields_autoplaced yes)
		(property "Reference" "Y1"
			(at 87.63 183.005 0)
			(effects
				(font
					(size 1.27 1.27)
					(thickness 0.15)
				)
			)
		)
		(property "Value" "Resonator_12MHz_ABM8G"
			(at 99.06 201.93 0)
			(effects
				(font
					(size 1.27 1.27)
					(thickness 0.15)
				)
				(justify left bottom)
				(hide yes)
			)
		)
		(property "Footprint" "antmicro-footprints:Resonator_SMD_Abracon_ABM8G_3.2x2.5mm"
			(at 99.06 204.47 0)
			(effects
				(font
					(size 1.27 1.27)
					(thickness 0.15)
				)
				(justify left bottom)
				(hide yes)
			)
		)
		(property "Datasheet" "https://abracon.com/Resonators/ABM8G.pdf"
			(at 99.06 207.01 0)
			(effects
				(font
					(size 1.27 1.27)
					(thickness 0.15)
				)
				(justify left bottom)
				(hide yes)
			)
		)
		(property "Description" ""
			(at 83.82 189.23 0)
			(effects
				(font
					(size 1.27 1.27)
				)
				(hide yes)
			)
		)
		(property "MPN" "ABM8G-12.000MHZ-18-D2Y-T"
			(at 99.06 196.85 0)
			(effects
				(font
					(size 1.27 1.27)
					(thickness 0.15)
				)
				(justify left bottom)
				(hide yes)
			)
		)
		(property "Manufacturer" "Abracon"
			(at 99.06 209.55 0)
			(effects
				(font
					(size 1.27 1.27)
					(thickness 0.15)
				)
				(justify left bottom)
				(hide yes)
			)
		)
		(property "Author" "Antmicro"
			(at 99.06 212.09 0)
			(effects
				(font
					(size 1.27 1.27)
					(thickness 0.15)
				)
				(justify left bottom)
				(hide yes)
			)
		)
		(property "License" "Apache-2.0"
			(at 99.06 214.63 0)
			(effects
				(font
					(size 1.27 1.27)
					(thickness 0.15)
				)
				(justify left bottom)
				(hide yes)
			)
		)
		(property "Val" "12 MHz"
			(at 87.63 185.5287 0)
			(effects
				(font
					(size 1.27 1.27)
					(thickness 0.15)
				)
			)
		)
		(pin "1"
		)
		(pin "2"
		)
		(pin "3"
		)
		(pin "4"
		)
		(instances
			(project "data-center-rdimm-ddr5-tester"
				(path ""
					(reference "Y1")
					(unit 1)
				)
			)
		)
	)
	(symbol
		(lib_id "antmicropower:PWR_FLAG")
		(at 233.68 54.61 0)
		(unit 1)
		(exclude_from_sim no)
		(in_bom yes)
		(on_board yes)
		(dnp no)
		(property "Reference" "#FLG01"
			(at 233.68 52.705 0)
			(effects
				(font
					(size 1.27 1.27)
				)
				(hide yes)
			)
		)
		(property "Value" "PWR_FLAG"
			(at 233.68 50.8 0)
			(effects
				(font
					(size 1.27 1.27)
				)
			)
		)
		(property "Footprint" ""
			(at 233.68 54.61 0)
			(effects
				(font
					(size 1.27 1.27)
				)
				(hide yes)
			)
		)
		(property "Datasheet" ""
			(at 233.68 54.61 0)
			(effects
				(font
					(size 1.27 1.27)
				)
				(hide yes)
			)
		)
		(property "Description" ""
			(at 233.68 54.61 0)
			(effects
				(font
					(size 1.27 1.27)
				)
				(hide yes)
			)
		)
		(pin "1"
		)
		(instances
			(project "data-center-rdimm-ddr5-tester"
				(path ""
					(reference "#FLG01")
					(unit 1)
				)
			)
		)
	)
	(symbol
		(lib_id "antmicropower:PWR_FLAG")
		(at 60.96 147.32 0)
		(unit 1)
		(exclude_from_sim no)
		(in_bom yes)
		(on_board yes)
		(dnp no)
		(fields_autoplaced yes)
		(property "Reference" "#FLG0101"
			(at 60.96 145.415 0)
			(effects
				(font
					(size 1.27 1.27)
				)
				(hide yes)
			)
		)
		(property "Value" "PWR_FLAG"
			(at 60.96 143.7442 0)
			(effects
				(font
					(size 1.27 1.27)
				)
			)
		)
		(property "Footprint" ""
			(at 60.96 147.32 0)
			(effects
				(font
					(size 1.27 1.27)
				)
				(hide yes)
			)
		)
		(property "Datasheet" ""
			(at 60.96 147.32 0)
			(effects
				(font
					(size 1.27 1.27)
				)
				(hide yes)
			)
		)
		(property "Description" ""
			(at 60.96 147.32 0)
			(effects
				(font
					(size 1.27 1.27)
				)
				(hide yes)
			)
		)
		(pin "1"
		)
		(instances
			(project "data-center-rdimm-ddr5-tester"
				(path ""
					(reference "#FLG0101")
					(unit 1)
				)
			)
		)
	)
	(symbol
		(lib_id "antmicroCapacitors0402:C_10u_6.3V_0402")
		(at 233.68 64.77 90)
		(unit 1)
		(exclude_from_sim no)
		(in_bom yes)
		(on_board yes)
		(dnp no)
		(fields_autoplaced yes)
		(property "Reference" "C113"
			(at 236.0041 61.393 90)
			(effects
				(font
					(size 1.27 1.27)
					(thickness 0.15)
				)
				(justify right)
			)
		)
		(property "Value" "C_10u_6.3V_0402"
			(at 243.84 44.45 0)
			(effects
				(font
					(size 1.27 1.27)
					(thickness 0.15)
				)
				(justify left bottom)
				(hide yes)
			)
		)
		(property "Footprint" "antmicro-footprints:C_0402_1005Metric"
			(at 246.38 44.45 0)
			(effects
				(font
					(size 1.27 1.27)
					(thickness 0.15)
				)
				(justify left bottom)
				(hide yes)
			)
		)
		(property "Datasheet" "https://www.murata.com/products/productdetail?partno=GRM155R60J106ME15%23"
			(at 248.92 44.45 0)
			(effects
				(font
					(size 1.27 1.27)
					(thickness 0.15)
				)
				(justify left bottom)
				(hide yes)
			)
		)
		(property "Description" ""
			(at 233.68 64.77 0)
			(effects
				(font
					(size 1.27 1.27)
				)
				(hide yes)
			)
		)
		(property "MPN" "GRM155R60J106ME15D"
			(at 251.46 44.45 0)
			(effects
				(font
					(size 1.27 1.27)
					(thickness 0.15)
				)
				(justify left bottom)
				(hide yes)
			)
		)
		(property "Manufacturer" "Murata"
			(at 254 44.45 0)
			(effects
				(font
					(size 1.27 1.27)
					(thickness 0.15)
				)
				(justify left bottom)
				(hide yes)
			)
		)
		(property "License" "Apache-2.0"
			(at 256.54 44.45 0)
			(effects
				(font
					(size 1.27 1.27)
					(thickness 0.15)
				)
				(justify left bottom)
				(hide yes)
			)
		)
		(property "Author" "Antmicro"
			(at 259.08 44.45 0)
			(effects
				(font
					(size 1.27 1.27)
					(thickness 0.15)
				)
				(justify left bottom)
				(hide yes)
			)
		)
		(property "Val" "10u"
			(at 236.0041 63.9167 90)
			(effects
				(font
					(size 1.27 1.27)
					(thickness 0.15)
				)
				(justify right)
			)
		)
		(property "Voltage" "6.3V"
			(at 261.62 44.45 0)
			(effects
				(font
					(size 1.27 1.27)
				)
				(justify left bottom)
				(hide yes)
			)
		)
		(property "Dielectric" "X5R"
			(at 264.16 44.45 0)
			(effects
				(font
					(size 1.27 1.27)
				)
				(justify left bottom)
				(hide yes)
			)
		)
		(pin "1"
		)
		(pin "2"
		)
		(instances
			(project "data-center-rdimm-ddr5-tester"
				(path ""
					(reference "C113")
					(unit 1)
				)
			)
		)
	)
	(symbol
		(lib_id "antmicroResistors0402:R_330R_0402")
		(at 134.62 266.7 0)
		(unit 1)
		(exclude_from_sim no)
		(in_bom yes)
		(on_board yes)
		(dnp no)
		(property "Reference" "R67"
			(at 139.7 266.7 0)
			(effects
				(font
					(size 1.27 1.27)
				)
				(justify left bottom)
			)
		)
		(property "Value" "R_330R_0402"
			(at 154.94 279.4 0)
			(effects
				(font
					(size 1.27 1.27)
					(thickness 0.15)
				)
				(justify left bottom)
				(hide yes)
			)
		)
		(property "Footprint" "antmicro-footprints:R_0402_1005Metric"
			(at 154.94 281.94 0)
			(effects
				(font
					(size 1.27 1.27)
					(thickness 0.15)
				)
				(justify left bottom)
				(hide yes)
			)
		)
		(property "Datasheet" "https://www.bourns.com/docs/product-datasheets/cr.pdf"
			(at 154.94 284.48 0)
			(effects
				(font
					(size 1.27 1.27)
					(thickness 0.15)
				)
				(justify left bottom)
				(hide yes)
			)
		)
		(property "Description" ""
			(at 134.62 266.7 0)
			(effects
				(font
					(size 1.27 1.27)
				)
				(hide yes)
			)
		)
		(property "Manufacturer" "Bourns"
			(at 154.94 289.56 0)
			(effects
				(font
					(size 1.27 1.27)
					(thickness 0.15)
				)
				(justify left bottom)
				(hide yes)
			)
		)
		(property "MPN" "CR0402-FX-3300GLF"
			(at 154.94 287.02 0)
			(effects
				(font
					(size 1.27 1.27)
					(thickness 0.15)
				)
				(justify left bottom)
				(hide yes)
			)
		)
		(property "Val" "330R"
			(at 129.54 266.7 0)
			(effects
				(font
					(size 1.27 1.27)
					(thickness 0.15)
				)
				(justify left bottom)
			)
		)
		(property "License" "Apache-2.0"
			(at 154.94 292.1 0)
			(effects
				(font
					(size 1.27 1.27)
					(thickness 0.15)
				)
				(justify left bottom)
				(hide yes)
			)
		)
		(property "Author" "Antmicro"
			(at 154.94 294.64 0)
			(effects
				(font
					(size 1.27 1.27)
					(thickness 0.15)
				)
				(justify left bottom)
				(hide yes)
			)
		)
		(property "Tolerance" "1%"
			(at 154.94 276.86 0)
			(effects
				(font
					(size 1.27 1.27)
				)
				(justify left bottom)
				(hide yes)
			)
		)
		(pin "1"
		)
		(pin "2"
		)
		(instances
			(project "data-center-rdimm-ddr5-tester"
				(path ""
					(reference "R67")
					(unit 1)
				)
			)
		)
	)
	(symbol
		(lib_id "antmicroLEDIndicationDiscrete:LED_G_0603_KP-1608CGCK")
		(at 116.84 252.73 0)
		(unit 1)
		(exclude_from_sim no)
		(in_bom yes)
		(on_board yes)
		(dnp no)
		(property "Reference" "D10"
			(at 123.825 251.46 0)
			(effects
				(font
					(size 1.27 1.27)
					(thickness 0.15)
				)
			)
		)
		(property "Value" "LED_G_0603_KP-1608CGCK"
			(at 139.7 260.35 0)
			(effects
				(font
					(size 1.27 1.27)
					(thickness 0.15)
				)
				(justify left bottom)
				(hide yes)
			)
		)
		(property "Footprint" "antmicro-footprints:LED_0603_1608Metric_G"
			(at 139.7 262.89 0)
			(effects
				(font
					(size 1.27 1.27)
					(thickness 0.15)
				)
				(justify left bottom)
				(hide yes)
			)
		)
		(property "Datasheet" "http://www.kingbright.com/attachments/file/psearch//000/00/00/KP-1608CGCK(Ver.23B).pdf"
			(at 139.7 265.43 0)
			(effects
				(font
					(size 1.27 1.27)
					(thickness 0.15)
				)
				(justify left bottom)
				(hide yes)
			)
		)
		(property "Description" ""
			(at 116.84 252.73 0)
			(effects
				(font
					(size 1.27 1.27)
				)
				(hide yes)
			)
		)
		(property "MPN" "KP-1608CGCK"
			(at 119.38 248.92 0)
			(effects
				(font
					(size 1.27 1.27)
					(thickness 0.15)
				)
			)
		)
		(property "Manufacturer" "Kingbright"
			(at 139.7 270.51 0)
			(effects
				(font
					(size 1.27 1.27)
					(thickness 0.15)
				)
				(justify left bottom)
				(hide yes)
			)
		)
		(property "Color" "Green"
			(at 114.935 251.46 0)
			(effects
				(font
					(size 1.27 1.27)
				)
			)
		)
		(property "Author" "Antmicro"
			(at 139.7 273.05 0)
			(effects
				(font
					(size 1.27 1.27)
					(thickness 0.15)
				)
				(justify left bottom)
				(hide yes)
			)
		)
		(property "License" "Apache-2.0"
			(at 139.7 275.59 0)
			(effects
				(font
					(size 1.27 1.27)
					(thickness 0.15)
				)
				(justify left bottom)
				(hide yes)
			)
		)
		(pin "1"
		)
		(pin "2"
		)
		(instances
			(project "data-center-rdimm-ddr5-tester"
				(path ""
					(reference "D10")
					(unit 1)
				)
			)
		)
	)
	(symbol
		(lib_id "antmicroResistors0402:R_47k_0402")
		(at 289.56 133.35 180)
		(unit 1)
		(exclude_from_sim no)
		(in_bom yes)
		(on_board yes)
		(dnp no)
		(property "Reference" "R51"
			(at 287.02 128.27 0)
			(effects
				(font
					(size 1.27 1.27)
				)
			)
		)
		(property "Value" "R_47k_0402"
			(at 269.24 120.65 0)
			(effects
				(font
					(size 1.27 1.27)
					(thickness 0.15)
				)
				(justify left bottom)
				(hide yes)
			)
		)
		(property "Footprint" "antmicro-footprints:R_0402_1005Metric"
			(at 269.24 118.11 0)
			(effects
				(font
					(size 1.27 1.27)
					(thickness 0.15)
				)
				(justify left bottom)
				(hide yes)
			)
		)
		(property "Datasheet" "https://www.bourns.com/docs/product-datasheets/cr.pdf"
			(at 269.24 115.57 0)
			(effects
				(font
					(size 1.27 1.27)
					(thickness 0.15)
				)
				(justify left bottom)
				(hide yes)
			)
		)
		(property "Description" ""
			(at 289.56 133.35 0)
			(effects
				(font
					(size 1.27 1.27)
				)
				(hide yes)
			)
		)
		(property "Manufacturer" "Bourns"
			(at 269.24 110.49 0)
			(effects
				(font
					(size 1.27 1.27)
					(thickness 0.15)
				)
				(justify left bottom)
				(hide yes)
			)
		)
		(property "MPN" "CR0402-FX-4702GLF"
			(at 269.24 113.03 0)
			(effects
				(font
					(size 1.27 1.27)
					(thickness 0.15)
				)
				(justify left bottom)
				(hide yes)
			)
		)
		(property "Val" "47k"
			(at 287.02 130.81 0)
			(effects
				(font
					(size 1.27 1.27)
					(thickness 0.15)
				)
			)
		)
		(property "License" "Apache-2.0"
			(at 269.24 107.95 0)
			(effects
				(font
					(size 1.27 1.27)
					(thickness 0.15)
				)
				(justify left bottom)
				(hide yes)
			)
		)
		(property "Author" "Antmicro"
			(at 269.24 105.41 0)
			(effects
				(font
					(size 1.27 1.27)
					(thickness 0.15)
				)
				(justify left bottom)
				(hide yes)
			)
		)
		(property "Tolerance" "1%"
			(at 269.24 123.19 0)
			(effects
				(font
					(size 1.27 1.27)
				)
				(justify left bottom)
				(hide yes)
			)
		)
		(pin "1"
		)
		(pin "2"
		)
		(instances
			(project "data-center-rdimm-ddr5-tester"
				(path ""
					(reference "R51")
					(unit 1)
				)
			)
		)
	)
	(symbol
		(lib_id "antmicroCapacitors0402:C_100n_0402")
		(at 372.11 205.74 90)
		(unit 1)
		(exclude_from_sim no)
		(in_bom yes)
		(on_board yes)
		(dnp no)
		(fields_autoplaced yes)
		(property "Reference" "C235"
			(at 374.4341 202.363 90)
			(effects
				(font
					(size 1.27 1.27)
					(thickness 0.15)
				)
				(justify right)
			)
		)
		(property "Value" "C_100n_0402"
			(at 382.27 185.42 0)
			(effects
				(font
					(size 1.27 1.27)
					(thickness 0.15)
				)
				(justify left bottom)
				(hide yes)
			)
		)
		(property "Footprint" "antmicro-footprints:C_0402_1005Metric"
			(at 384.81 185.42 0)
			(effects
				(font
					(size 1.27 1.27)
					(thickness 0.15)
				)
				(justify left bottom)
				(hide yes)
			)
		)
		(property "Datasheet" "https://www.murata.com/products/productdetail?partno=GRM155R61H104KE14%23"
			(at 387.35 185.42 0)
			(effects
				(font
					(size 1.27 1.27)
					(thickness 0.15)
				)
				(justify left bottom)
				(hide yes)
			)
		)
		(property "Description" ""
			(at 372.11 205.74 0)
			(effects
				(font
					(size 1.27 1.27)
				)
				(hide yes)
			)
		)
		(property "MPN" "GRM155R61H104KE14D"
			(at 389.89 185.42 0)
			(effects
				(font
					(size 1.27 1.27)
					(thickness 0.15)
				)
				(justify left bottom)
				(hide yes)
			)
		)
		(property "Manufacturer" "Murata"
			(at 392.43 185.42 0)
			(effects
				(font
					(size 1.27 1.27)
					(thickness 0.15)
				)
				(justify left bottom)
				(hide yes)
			)
		)
		(property "License" "Apache-2.0"
			(at 394.97 185.42 0)
			(effects
				(font
					(size 1.27 1.27)
					(thickness 0.15)
				)
				(justify left bottom)
				(hide yes)
			)
		)
		(property "Author" "Antmicro"
			(at 397.51 185.42 0)
			(effects
				(font
					(size 1.27 1.27)
					(thickness 0.15)
				)
				(justify left bottom)
				(hide yes)
			)
		)
		(property "Val" "100n"
			(at 374.4341 204.8867 90)
			(effects
				(font
					(size 1.27 1.27)
					(thickness 0.15)
				)
				(justify right)
			)
		)
		(property "Voltage" "50V"
			(at 400.05 185.42 0)
			(effects
				(font
					(size 1.27 1.27)
				)
				(justify left bottom)
				(hide yes)
			)
		)
		(property "Dielectric" "X5R"
			(at 402.59 185.42 0)
			(effects
				(font
					(size 1.27 1.27)
				)
				(justify left bottom)
				(hide yes)
			)
		)
		(pin "1"
		)
		(pin "2"
		)
		(instances
			(project "data-center-rdimm-ddr5-tester"
				(path ""
					(reference "C235")
					(unit 1)
				)
			)
		)
	)
	(symbol
		(lib_id "antmicropower:GND")
		(at 91.44 49.53 0)
		(mirror y)
		(unit 1)
		(exclude_from_sim no)
		(in_bom yes)
		(on_board yes)
		(dnp no)
		(fields_autoplaced yes)
		(property "Reference" "#PWR0507"
			(at 91.44 55.88 0)
			(effects
				(font
					(size 1.27 1.27)
				)
				(hide yes)
			)
		)
		(property "Value" "GND"
			(at 91.44 53.975 0)
			(effects
				(font
					(size 1.27 1.27)
					(thickness 0.15)
				)
			)
		)
		(property "Footprint" ""
			(at 82.55 57.15 0)
			(effects
				(font
					(size 1.27 1.27)
					(thickness 0.15)
				)
				(justify left bottom)
				(hide yes)
			)
		)
		(property "Datasheet" ""
			(at 82.55 62.23 0)
			(effects
				(font
					(size 1.27 1.27)
					(thickness 0.15)
				)
				(justify left bottom)
				(hide yes)
			)
		)
		(property "Description" ""
			(at 91.44 49.53 0)
			(effects
				(font
					(size 1.27 1.27)
				)
				(hide yes)
			)
		)
		(property "Author" "Antmicro"
			(at 82.55 54.61 0)
			(effects
				(font
					(size 1.27 1.27)
					(thickness 0.15)
				)
				(justify left bottom)
				(hide yes)
			)
		)
		(property "License" "Apache-2.0"
			(at 82.55 57.15 0)
			(effects
				(font
					(size 1.27 1.27)
					(thickness 0.15)
				)
				(justify left bottom)
				(hide yes)
			)
		)
		(pin "1"
		)
		(instances
			(project "data-center-rdimm-ddr5-tester"
				(path ""
					(reference "#PWR0507")
					(unit 1)
				)
			)
		)
	)
	(symbol
		(lib_id "antmicroResistors0402:R_22R_0402")
		(at 173.99 160.02 0)
		(unit 1)
		(exclude_from_sim no)
		(in_bom no)
		(on_board yes)
		(dnp yes)
		(property "Reference" "R60"
			(at 180.975 158.75 0)
			(effects
				(font
					(size 1.27 1.27)
				)
			)
		)
		(property "Value" "R_22R_0402"
			(at 194.31 172.72 0)
			(effects
				(font
					(size 1.27 1.27)
					(thickness 0.15)
				)
				(justify left bottom)
				(hide yes)
			)
		)
		(property "Footprint" "antmicro-footprints:R_0402_1005Metric"
			(at 194.31 175.26 0)
			(effects
				(font
					(size 1.27 1.27)
					(thickness 0.15)
				)
				(justify left bottom)
				(hide yes)
			)
		)
		(property "Datasheet" "https://www.bourns.com/docs/product-datasheets/cr.pdf"
			(at 194.31 177.8 0)
			(effects
				(font
					(size 1.27 1.27)
					(thickness 0.15)
				)
				(justify left bottom)
				(hide yes)
			)
		)
		(property "Description" ""
			(at 173.99 160.02 0)
			(effects
				(font
					(size 1.27 1.27)
				)
				(hide yes)
			)
		)
		(property "Manufacturer" "Bourns"
			(at 194.31 182.88 0)
			(effects
				(font
					(size 1.27 1.27)
					(thickness 0.15)
				)
				(justify left bottom)
				(hide yes)
			)
		)
		(property "MPN" "CR0402-FX-22R0GLF"
			(at 194.31 180.34 0)
			(effects
				(font
					(size 1.27 1.27)
					(thickness 0.15)
				)
				(justify left bottom)
				(hide yes)
			)
		)
		(property "Val" "22R"
			(at 172.085 158.75 0)
			(effects
				(font
					(size 1.27 1.27)
					(thickness 0.15)
				)
			)
		)
		(property "License" "Apache-2.0"
			(at 194.31 185.42 0)
			(effects
				(font
					(size 1.27 1.27)
					(thickness 0.15)
				)
				(justify left bottom)
				(hide yes)
			)
		)
		(property "Author" "Antmicro"
			(at 194.31 187.96 0)
			(effects
				(font
					(size 1.27 1.27)
					(thickness 0.15)
				)
				(justify left bottom)
				(hide yes)
			)
		)
		(property "Tolerance" "1%"
			(at 194.31 170.18 0)
			(effects
				(font
					(size 1.27 1.27)
				)
				(justify left bottom)
				(hide yes)
			)
		)
		(pin "1"
		)
		(pin "2"
		)
		(instances
			(project "data-center-rdimm-ddr5-tester"
				(path ""
					(reference "R60")
					(unit 1)
				)
			)
		)
	)
	(symbol
		(lib_id "antmicropower:GND")
		(at 384.81 226.06 0)
		(unit 1)
		(exclude_from_sim no)
		(in_bom yes)
		(on_board yes)
		(dnp no)
		(property "Reference" "#PWR017"
			(at 384.81 232.41 0)
			(effects
				(font
					(size 1.27 1.27)
				)
				(hide yes)
			)
		)
		(property "Value" "GND"
			(at 382.905 230.505 0)
			(effects
				(font
					(size 1.27 1.27)
					(thickness 0.15)
				)
				(justify left bottom)
			)
		)
		(property "Footprint" ""
			(at 393.7 233.68 0)
			(effects
				(font
					(size 1.27 1.27)
					(thickness 0.15)
				)
				(justify left bottom)
				(hide yes)
			)
		)
		(property "Datasheet" ""
			(at 393.7 238.76 0)
			(effects
				(font
					(size 1.27 1.27)
					(thickness 0.15)
				)
				(justify left bottom)
				(hide yes)
			)
		)
		(property "Description" ""
			(at 384.81 226.06 0)
			(effects
				(font
					(size 1.27 1.27)
				)
				(hide yes)
			)
		)
		(property "Author" "Antmicro"
			(at 393.7 231.14 0)
			(effects
				(font
					(size 1.27 1.27)
					(thickness 0.15)
				)
				(justify left bottom)
				(hide yes)
			)
		)
		(property "License" "Apache-2.0"
			(at 393.7 233.68 0)
			(effects
				(font
					(size 1.27 1.27)
					(thickness 0.15)
				)
				(justify left bottom)
				(hide yes)
			)
		)
		(pin "1"
		)
		(instances
			(project "data-center-rdimm-ddr5-tester"
				(path ""
					(reference "#PWR017")
					(unit 1)
				)
			)
		)
	)
	(symbol
		(lib_id "antmicroResistors0402:R_330R_0402")
		(at 76.2 80.01 0)
		(mirror y)
		(unit 1)
		(exclude_from_sim no)
		(in_bom yes)
		(on_board yes)
		(dnp no)
		(property "Reference" "R90"
			(at 73.66 74.93 0)
			(effects
				(font
					(size 1.27 1.27)
				)
			)
		)
		(property "Value" "R_330R_0402"
			(at 55.88 92.71 0)
			(effects
				(font
					(size 1.27 1.27)
					(thickness 0.15)
				)
				(justify left bottom)
				(hide yes)
			)
		)
		(property "Footprint" "antmicro-footprints:R_0402_1005Metric"
			(at 55.88 95.25 0)
			(effects
				(font
					(size 1.27 1.27)
					(thickness 0.15)
				)
				(justify left bottom)
				(hide yes)
			)
		)
		(property "Datasheet" "https://www.bourns.com/docs/product-datasheets/cr.pdf"
			(at 55.88 97.79 0)
			(effects
				(font
					(size 1.27 1.27)
					(thickness 0.15)
				)
				(justify left bottom)
				(hide yes)
			)
		)
		(property "Description" ""
			(at 76.2 80.01 0)
			(effects
				(font
					(size 1.27 1.27)
				)
				(hide yes)
			)
		)
		(property "Manufacturer" "Bourns"
			(at 55.88 102.87 0)
			(effects
				(font
					(size 1.27 1.27)
					(thickness 0.15)
				)
				(justify left bottom)
				(hide yes)
			)
		)
		(property "MPN" "CR0402-FX-3300GLF"
			(at 55.88 100.33 0)
			(effects
				(font
					(size 1.27 1.27)
					(thickness 0.15)
				)
				(justify left bottom)
				(hide yes)
			)
		)
		(property "Val" "330R"
			(at 73.66 77.47 0)
			(effects
				(font
					(size 1.27 1.27)
					(thickness 0.15)
				)
			)
		)
		(property "License" "Apache-2.0"
			(at 55.88 105.41 0)
			(effects
				(font
					(size 1.27 1.27)
					(thickness 0.15)
				)
				(justify left bottom)
				(hide yes)
			)
		)
		(property "Author" "Antmicro"
			(at 55.88 107.95 0)
			(effects
				(font
					(size 1.27 1.27)
					(thickness 0.15)
				)
				(justify left bottom)
				(hide yes)
			)
		)
		(property "Tolerance" "1%"
			(at 55.88 90.17 0)
			(effects
				(font
					(size 1.27 1.27)
				)
				(justify left bottom)
				(hide yes)
			)
		)
		(pin "1"
		)
		(pin "2"
		)
		(instances
			(project "data-center-rdimm-ddr5-tester"
				(path ""
					(reference "R90")
					(unit 1)
				)
			)
		)
	)
	(symbol
		(lib_id "antmicropower:+3V3_AON")
		(at 278.13 160.02 0)
		(mirror y)
		(unit 1)
		(exclude_from_sim no)
		(in_bom yes)
		(on_board yes)
		(dnp no)
		(property "Reference" "#PWR0193"
			(at 278.13 163.83 0)
			(effects
				(font
					(size 1.27 1.27)
				)
				(hide yes)
			)
		)
		(property "Value" "+3V3_AON"
			(at 283.845 156.845 0)
			(effects
				(font
					(size 1.27 1.27)
				)
			)
		)
		(property "Footprint" ""
			(at 278.13 160.02 0)
			(effects
				(font
					(size 1.27 1.27)
				)
				(hide yes)
			)
		)
		(property "Datasheet" ""
			(at 278.13 160.02 0)
			(effects
				(font
					(size 1.27 1.27)
				)
				(hide yes)
			)
		)
		(property "Description" ""
			(at 278.13 160.02 0)
			(effects
				(font
					(size 1.27 1.27)
				)
				(hide yes)
			)
		)
		(pin "1"
		)
		(instances
			(project "data-center-rdimm-ddr5-tester"
				(path ""
					(reference "#PWR0193")
					(unit 1)
				)
			)
		)
	)
	(symbol
		(lib_id "antmicropower:+3V3_AON")
		(at 320.04 158.75 0)
		(mirror y)
		(unit 1)
		(exclude_from_sim no)
		(in_bom yes)
		(on_board yes)
		(dnp no)
		(property "Reference" "#PWR0191"
			(at 320.04 162.56 0)
			(effects
				(font
					(size 1.27 1.27)
				)
				(hide yes)
			)
		)
		(property "Value" "+3V3_AON"
			(at 325.755 155.575 0)
			(effects
				(font
					(size 1.27 1.27)
				)
			)
		)
		(property "Footprint" ""
			(at 320.04 158.75 0)
			(effects
				(font
					(size 1.27 1.27)
				)
				(hide yes)
			)
		)
		(property "Datasheet" ""
			(at 320.04 158.75 0)
			(effects
				(font
					(size 1.27 1.27)
				)
				(hide yes)
			)
		)
		(property "Description" ""
			(at 320.04 158.75 0)
			(effects
				(font
					(size 1.27 1.27)
				)
				(hide yes)
			)
		)
		(pin "1"
		)
		(instances
			(project "data-center-rdimm-ddr5-tester"
				(path ""
					(reference "#PWR0191")
					(unit 1)
				)
			)
		)
	)
	(symbol
		(lib_id "antmicropower:GND")
		(at 365.76 83.82 0)
		(unit 1)
		(exclude_from_sim no)
		(in_bom yes)
		(on_board yes)
		(dnp no)
		(fields_autoplaced yes)
		(property "Reference" "#PWR0523"
			(at 365.76 90.17 0)
			(effects
				(font
					(size 1.27 1.27)
				)
				(hide yes)
			)
		)
		(property "Value" "GND"
			(at 363.855 88.265 0)
			(effects
				(font
					(size 1.27 1.27)
					(thickness 0.15)
				)
				(justify left bottom)
			)
		)
		(property "Footprint" ""
			(at 374.65 91.44 0)
			(effects
				(font
					(size 1.27 1.27)
					(thickness 0.15)
				)
				(justify left bottom)
				(hide yes)
			)
		)
		(property "Datasheet" ""
			(at 374.65 96.52 0)
			(effects
				(font
					(size 1.27 1.27)
					(thickness 0.15)
				)
				(justify left bottom)
				(hide yes)
			)
		)
		(property "Description" ""
			(at 365.76 83.82 0)
			(effects
				(font
					(size 1.27 1.27)
				)
				(hide yes)
			)
		)
		(property "Author" "Antmicro"
			(at 374.65 88.9 0)
			(effects
				(font
					(size 1.27 1.27)
					(thickness 0.15)
				)
				(justify left bottom)
				(hide yes)
			)
		)
		(property "License" "Apache-2.0"
			(at 374.65 91.44 0)
			(effects
				(font
					(size 1.27 1.27)
					(thickness 0.15)
				)
				(justify left bottom)
				(hide yes)
			)
		)
		(pin "1"
		)
		(instances
			(project "data-center-rdimm-ddr5-tester"
				(path ""
					(reference "#PWR0523")
					(unit 1)
				)
			)
		)
	)
	(symbol
		(lib_id "antmicroLogicTranslatorsLevelShifters:TXS0102DQER")
		(at 257.81 200.66 0)
		(unit 1)
		(exclude_from_sim no)
		(in_bom yes)
		(on_board yes)
		(dnp no)
		(fields_autoplaced yes)
		(property "Reference" "U16"
			(at 266.7 195.58 0)
			(effects
				(font
					(size 1.27 1.27)
					(thickness 0.15)
				)
			)
		)
		(property "Value" "TXS0102DQER"
			(at 290.83 208.28 0)
			(effects
				(font
					(size 1.27 1.27)
					(thickness 0.15)
				)
				(justify left bottom)
				(hide yes)
			)
		)
		(property "Footprint" "antmicro-footprints:X2SON8_1.4x1x0.32mm_P0.35mm"
			(at 290.83 210.82 0)
			(effects
				(font
					(size 1.27 1.27)
					(thickness 0.15)
				)
				(justify left bottom)
				(hide yes)
			)
		)
		(property "Datasheet" "https://www.ti.com/lit/ds/symlink/txs0102.pdf?ts=1637914596981&ref_url=https%253A%252F%252Fwww.ti.com%252Fstore%252Fti%252Fen%252Fp%252Fproduct%252F%253Fp%253DTXS0102DCTR%2526keyMatch%253DTXS0102DCTR%2526tisearch%253Dsearch-everything%2526usecase%253DOPN"
			(at 290.83 213.36 0)
			(effects
				(font
					(size 1.27 1.27)
					(thickness 0.15)
				)
				(justify left bottom)
				(hide yes)
			)
		)
		(property "Description" ""
			(at 257.81 200.66 0)
			(effects
				(font
					(size 1.27 1.27)
				)
				(hide yes)
			)
		)
		(property "MPN" "TXS0102DQER"
			(at 266.7 198.12 0)
			(effects
				(font
					(size 1.27 1.27)
					(thickness 0.15)
				)
			)
		)
		(property "Manufacturer" "Texas Instruments"
			(at 290.83 218.44 0)
			(effects
				(font
					(size 1.27 1.27)
					(thickness 0.15)
				)
				(justify left bottom)
				(hide yes)
			)
		)
		(property "Author" "Antmicro"
			(at 290.83 220.98 0)
			(effects
				(font
					(size 1.27 1.27)
					(thickness 0.15)
				)
				(justify left bottom)
				(hide yes)
			)
		)
		(property "License" "Apache-2.0"
			(at 290.83 223.52 0)
			(effects
				(font
					(size 1.27 1.27)
					(thickness 0.15)
				)
				(justify left bottom)
				(hide yes)
			)
		)
		(pin "2"
		)
		(pin "7"
		)
		(pin "5"
		)
		(pin "6"
		)
		(pin "8"
		)
		(pin "3"
		)
		(pin "4"
		)
		(pin "1"
		)
		(instances
			(project "data-center-rdimm-ddr5-tester"
				(path ""
					(reference "U16")
					(unit 1)
				)
			)
		)
	)
	(symbol
		(lib_name "SN74HC595B_1")
		(lib_id "antmicroLogicShiftRegisters:SN74HC595B")
		(at 176.53 248.92 0)
		(mirror y)
		(unit 1)
		(exclude_from_sim no)
		(in_bom yes)
		(on_board yes)
		(dnp no)
		(property "Reference" "U9"
			(at 166.37 241.3 0)
			(effects
				(font
					(size 1.27 1.27)
					(thickness 0.15)
				)
			)
		)
		(property "Value" "SN74HC595B"
			(at 140.97 266.7 0)
			(effects
				(font
					(size 1.27 1.27)
					(thickness 0.15)
				)
				(justify left bottom)
				(hide yes)
			)
		)
		(property "Footprint" "antmicro-footprints:X1QFN-16-1EP_2.5x2.5mm"
			(at 140.97 259.08 0)
			(effects
				(font
					(size 1.27 1.27)
					(thickness 0.15)
				)
				(justify left bottom)
				(hide yes)
			)
		)
		(property "Datasheet" "https://www.ti.com/general/docs/suppproductinfo.tsp?distId=26&gotoUrl=https://www.ti.com/lit/gpn/sn74hc595b"
			(at 140.97 261.62 0)
			(effects
				(font
					(size 1.27 1.27)
					(thickness 0.15)
				)
				(justify left bottom)
				(hide yes)
			)
		)
		(property "Description" ""
			(at 176.53 248.92 0)
			(effects
				(font
					(size 1.27 1.27)
				)
				(hide yes)
			)
		)
		(property "MPN" "SN74HC595BRWNR"
			(at 166.37 243.84 0)
			(effects
				(font
					(size 1.27 1.27)
					(thickness 0.15)
				)
			)
		)
		(property "Manufacturer" "Texas Instruments"
			(at 140.97 264.16 0)
			(effects
				(font
					(size 1.27 1.27)
					(thickness 0.15)
				)
				(justify left bottom)
				(hide yes)
			)
		)
		(property "Author" "Antmicro"
			(at 140.97 269.24 0)
			(effects
				(font
					(size 1.27 1.27)
					(thickness 0.15)
				)
				(justify left bottom)
				(hide yes)
			)
		)
		(property "License" "Apache-2.0"
			(at 140.97 271.78 0)
			(effects
				(font
					(size 1.27 1.27)
					(thickness 0.15)
				)
				(justify left bottom)
				(hide yes)
			)
		)
		(pin "9"
		)
		(pin "8"
		)
		(pin "10"
		)
		(pin "15"
		)
		(pin "6"
		)
		(pin "1"
		)
		(pin "12"
		)
		(pin "14"
		)
		(pin "13"
		)
		(pin "7"
		)
		(pin "2"
		)
		(pin "17"
		)
		(pin "5"
		)
		(pin "16"
		)
		(pin "4"
		)
		(pin "11"
		)
		(pin "3"
		)
		(instances
			(project "data-center-rdimm-ddr5-tester"
				(path ""
					(reference "U9")
					(unit 1)
				)
			)
		)
	)
	(symbol
		(lib_id "antmicropower:GND")
		(at 256.54 149.86 0)
		(unit 1)
		(exclude_from_sim no)
		(in_bom yes)
		(on_board yes)
		(dnp no)
		(property "Reference" "#PWR0204"
			(at 256.54 156.21 0)
			(effects
				(font
					(size 1.27 1.27)
				)
				(hide yes)
			)
		)
		(property "Value" "GND"
			(at 254.635 154.305 0)
			(effects
				(font
					(size 1.27 1.27)
					(thickness 0.15)
				)
				(justify left bottom)
			)
		)
		(property "Footprint" ""
			(at 265.43 157.48 0)
			(effects
				(font
					(size 1.27 1.27)
					(thickness 0.15)
				)
				(justify left bottom)
				(hide yes)
			)
		)
		(property "Datasheet" ""
			(at 265.43 162.56 0)
			(effects
				(font
					(size 1.27 1.27)
					(thickness 0.15)
				)
				(justify left bottom)
				(hide yes)
			)
		)
		(property "Description" ""
			(at 256.54 149.86 0)
			(effects
				(font
					(size 1.27 1.27)
				)
				(hide yes)
			)
		)
		(property "Author" "Antmicro"
			(at 265.43 154.94 0)
			(effects
				(font
					(size 1.27 1.27)
					(thickness 0.15)
				)
				(justify left bottom)
				(hide yes)
			)
		)
		(property "License" "Apache-2.0"
			(at 265.43 157.48 0)
			(effects
				(font
					(size 1.27 1.27)
					(thickness 0.15)
				)
				(justify left bottom)
				(hide yes)
			)
		)
		(pin "1"
		)
		(instances
			(project "data-center-rdimm-ddr5-tester"
				(path ""
					(reference "#PWR0204")
					(unit 1)
				)
			)
		)
	)
	(symbol
		(lib_id "antmicropower:GND")
		(at 391.16 83.82 0)
		(unit 1)
		(exclude_from_sim no)
		(in_bom yes)
		(on_board yes)
		(dnp no)
		(fields_autoplaced yes)
		(property "Reference" "#PWR0524"
			(at 391.16 90.17 0)
			(effects
				(font
					(size 1.27 1.27)
				)
				(hide yes)
			)
		)
		(property "Value" "GND"
			(at 389.255 88.265 0)
			(effects
				(font
					(size 1.27 1.27)
					(thickness 0.15)
				)
				(justify left bottom)
			)
		)
		(property "Footprint" ""
			(at 400.05 91.44 0)
			(effects
				(font
					(size 1.27 1.27)
					(thickness 0.15)
				)
				(justify left bottom)
				(hide yes)
			)
		)
		(property "Datasheet" ""
			(at 400.05 96.52 0)
			(effects
				(font
					(size 1.27 1.27)
					(thickness 0.15)
				)
				(justify left bottom)
				(hide yes)
			)
		)
		(property "Description" ""
			(at 391.16 83.82 0)
			(effects
				(font
					(size 1.27 1.27)
				)
				(hide yes)
			)
		)
		(property "Author" "Antmicro"
			(at 400.05 88.9 0)
			(effects
				(font
					(size 1.27 1.27)
					(thickness 0.15)
				)
				(justify left bottom)
				(hide yes)
			)
		)
		(property "License" "Apache-2.0"
			(at 400.05 91.44 0)
			(effects
				(font
					(size 1.27 1.27)
					(thickness 0.15)
				)
				(justify left bottom)
				(hide yes)
			)
		)
		(pin "1"
		)
		(instances
			(project "data-center-rdimm-ddr5-tester"
				(path ""
					(reference "#PWR0524")
					(unit 1)
				)
			)
		)
	)
	(symbol
		(lib_id "antmicroResistors0402:R_22R_0402")
		(at 173.99 152.4 0)
		(unit 1)
		(exclude_from_sim no)
		(in_bom no)
		(on_board yes)
		(dnp yes)
		(property "Reference" "R58"
			(at 180.975 151.13 0)
			(effects
				(font
					(size 1.27 1.27)
				)
			)
		)
		(property "Value" "R_22R_0402"
			(at 194.31 165.1 0)
			(effects
				(font
					(size 1.27 1.27)
					(thickness 0.15)
				)
				(justify left bottom)
				(hide yes)
			)
		)
		(property "Footprint" "antmicro-footprints:R_0402_1005Metric"
			(at 194.31 167.64 0)
			(effects
				(font
					(size 1.27 1.27)
					(thickness 0.15)
				)
				(justify left bottom)
				(hide yes)
			)
		)
		(property "Datasheet" "https://www.bourns.com/docs/product-datasheets/cr.pdf"
			(at 194.31 170.18 0)
			(effects
				(font
					(size 1.27 1.27)
					(thickness 0.15)
				)
				(justify left bottom)
				(hide yes)
			)
		)
		(property "Description" ""
			(at 173.99 152.4 0)
			(effects
				(font
					(size 1.27 1.27)
				)
				(hide yes)
			)
		)
		(property "Manufacturer" "Bourns"
			(at 194.31 175.26 0)
			(effects
				(font
					(size 1.27 1.27)
					(thickness 0.15)
				)
				(justify left bottom)
				(hide yes)
			)
		)
		(property "MPN" "CR0402-FX-22R0GLF"
			(at 194.31 172.72 0)
			(effects
				(font
					(size 1.27 1.27)
					(thickness 0.15)
				)
				(justify left bottom)
				(hide yes)
			)
		)
		(property "Val" "22R"
			(at 172.085 151.13 0)
			(effects
				(font
					(size 1.27 1.27)
					(thickness 0.15)
				)
			)
		)
		(property "License" "Apache-2.0"
			(at 194.31 177.8 0)
			(effects
				(font
					(size 1.27 1.27)
					(thickness 0.15)
				)
				(justify left bottom)
				(hide yes)
			)
		)
		(property "Author" "Antmicro"
			(at 194.31 180.34 0)
			(effects
				(font
					(size 1.27 1.27)
					(thickness 0.15)
				)
				(justify left bottom)
				(hide yes)
			)
		)
		(property "Tolerance" "1%"
			(at 194.31 162.56 0)
			(effects
				(font
					(size 1.27 1.27)
				)
				(justify left bottom)
				(hide yes)
			)
		)
		(pin "1"
		)
		(pin "2"
		)
		(instances
			(project "data-center-rdimm-ddr5-tester"
				(path ""
					(reference "R58")
					(unit 1)
				)
			)
		)
	)
	(symbol
		(lib_id "antmicroResistors0402:R_0R_0402")
		(at 308.61 176.53 180)
		(unit 1)
		(exclude_from_sim no)
		(in_bom yes)
		(on_board yes)
		(dnp no)
		(property "Reference" "R93"
			(at 311.15 175.26 0)
			(effects
				(font
					(size 1.27 1.27)
				)
			)
		)
		(property "Value" "R_0R_0402"
			(at 288.29 163.83 0)
			(effects
				(font
					(size 1.27 1.27)
					(thickness 0.15)
				)
				(justify left bottom)
				(hide yes)
			)
		)
		(property "Footprint" "antmicro-footprints:R_0402_1005Metric"
			(at 288.29 161.29 0)
			(effects
				(font
					(size 1.27 1.27)
					(thickness 0.15)
				)
				(justify left bottom)
				(hide yes)
			)
		)
		(property "Datasheet" "https://industrial.panasonic.com/cdbs/www-data/pdf/RDA0000/AOA0000C301.pdf"
			(at 288.29 158.75 0)
			(effects
				(font
					(size 1.27 1.27)
					(thickness 0.15)
				)
				(justify left bottom)
				(hide yes)
			)
		)
		(property "Description" ""
			(at 308.61 176.53 0)
			(effects
				(font
					(size 1.27 1.27)
				)
				(hide yes)
			)
		)
		(property "Manufacturer" "Panasonic"
			(at 288.29 153.67 0)
			(effects
				(font
					(size 1.27 1.27)
					(thickness 0.15)
				)
				(justify left bottom)
				(hide yes)
			)
		)
		(property "MPN" "ERJ2GE0R00X"
			(at 288.29 156.21 0)
			(effects
				(font
					(size 1.27 1.27)
					(thickness 0.15)
				)
				(justify left bottom)
				(hide yes)
			)
		)
		(property "Val" "0R"
			(at 302.26 175.26 0)
			(effects
				(font
					(size 1.27 1.27)
					(thickness 0.15)
				)
			)
		)
		(property "License" "Apache-2.0"
			(at 288.29 151.13 0)
			(effects
				(font
					(size 1.27 1.27)
					(thickness 0.15)
				)
				(justify left bottom)
				(hide yes)
			)
		)
		(property "Author" "Antmicro"
			(at 288.29 148.59 0)
			(effects
				(font
					(size 1.27 1.27)
					(thickness 0.15)
				)
				(justify left bottom)
				(hide yes)
			)
		)
		(property "Tolerance" "~"
			(at 288.29 166.37 0)
			(effects
				(font
					(size 1.27 1.27)
				)
				(justify left bottom)
				(hide yes)
			)
		)
		(property "Current" "1A"
			(at 306.07 172.72 0)
			(effects
				(font
					(size 1.27 1.27)
					(thickness 0.15)
				)
				(hide yes)
			)
		)
		(pin "1"
		)
		(pin "2"
		)
		(instances
			(project "data-center-rdimm-ddr5-tester"
				(path ""
					(reference "R93")
					(unit 1)
				)
			)
		)
	)
	(symbol
		(lib_id "antmicroCapacitors0402:C_100n_0402")
		(at 71.12 88.9 0)
		(mirror x)
		(unit 1)
		(exclude_from_sim no)
		(in_bom yes)
		(on_board yes)
		(dnp no)
		(property "Reference" "C133"
			(at 73.6536 83.185 0)
			(effects
				(font
					(size 1.27 1.27)
				)
			)
		)
		(property "Value" "C_100n_0402"
			(at 91.44 78.74 0)
			(effects
				(font
					(size 1.27 1.27)
					(thickness 0.15)
				)
				(justify left bottom)
				(hide yes)
			)
		)
		(property "Footprint" "antmicro-footprints:C_0402_1005Metric"
			(at 91.44 76.2 0)
			(effects
				(font
					(size 1.27 1.27)
					(thickness 0.15)
				)
				(justify left bottom)
				(hide yes)
			)
		)
		(property "Datasheet" "https://www.murata.com/products/productdetail?partno=GRM155R61H104KE14%23"
			(at 91.44 73.66 0)
			(effects
				(font
					(size 1.27 1.27)
					(thickness 0.15)
				)
				(justify left bottom)
				(hide yes)
			)
		)
		(property "Description" ""
			(at 71.12 88.9 0)
			(effects
				(font
					(size 1.27 1.27)
				)
				(hide yes)
			)
		)
		(property "Manufacturer" "Murata"
			(at 91.44 68.58 0)
			(effects
				(font
					(size 1.27 1.27)
					(thickness 0.15)
				)
				(justify left bottom)
				(hide yes)
			)
		)
		(property "MPN" "GRM155R61H104KE14D"
			(at 91.44 71.12 0)
			(effects
				(font
					(size 1.27 1.27)
					(thickness 0.15)
				)
				(justify left bottom)
				(hide yes)
			)
		)
		(property "Val" "100n"
			(at 73.66 85.725 0)
			(effects
				(font
					(size 1.27 1.27)
					(thickness 0.15)
				)
			)
		)
		(property "License" "Apache-2.0"
			(at 91.44 66.04 0)
			(effects
				(font
					(size 1.27 1.27)
					(thickness 0.15)
				)
				(justify left bottom)
				(hide yes)
			)
		)
		(property "Author" "Antmicro"
			(at 91.44 63.5 0)
			(effects
				(font
					(size 1.27 1.27)
					(thickness 0.15)
				)
				(justify left bottom)
				(hide yes)
			)
		)
		(property "Voltage" "50V"
			(at 91.44 60.96 0)
			(effects
				(font
					(size 1.27 1.27)
				)
				(justify left bottom)
				(hide yes)
			)
		)
		(property "Dielectric" "X5R"
			(at 91.44 58.42 0)
			(effects
				(font
					(size 1.27 1.27)
				)
				(justify left bottom)
				(hide yes)
			)
		)
		(pin "1"
		)
		(pin "2"
		)
		(instances
			(project "data-center-rdimm-ddr5-tester"
				(path ""
					(reference "C133")
					(unit 1)
				)
			)
		)
	)
	(symbol
		(lib_id "antmicroLogicTranslatorsLevelShifters:TXS0102DQER")
		(at 257.81 222.25 0)
		(unit 1)
		(exclude_from_sim no)
		(in_bom yes)
		(on_board yes)
		(dnp no)
		(fields_autoplaced yes)
		(property "Reference" "U32"
			(at 266.7 217.17 0)
			(effects
				(font
					(size 1.27 1.27)
					(thickness 0.15)
				)
			)
		)
		(property "Value" "TXS0102DQER"
			(at 290.83 229.87 0)
			(effects
				(font
					(size 1.27 1.27)
					(thickness 0.15)
				)
				(justify left bottom)
				(hide yes)
			)
		)
		(property "Footprint" "antmicro-footprints:X2SON8_1.4x1x0.32mm_P0.35mm"
			(at 290.83 232.41 0)
			(effects
				(font
					(size 1.27 1.27)
					(thickness 0.15)
				)
				(justify left bottom)
				(hide yes)
			)
		)
		(property "Datasheet" "https://www.ti.com/lit/ds/symlink/txs0102.pdf?ts=1637914596981&ref_url=https%253A%252F%252Fwww.ti.com%252Fstore%252Fti%252Fen%252Fp%252Fproduct%252F%253Fp%253DTXS0102DCTR%2526keyMatch%253DTXS0102DCTR%2526tisearch%253Dsearch-everything%2526usecase%253DOPN"
			(at 290.83 234.95 0)
			(effects
				(font
					(size 1.27 1.27)
					(thickness 0.15)
				)
				(justify left bottom)
				(hide yes)
			)
		)
		(property "Description" ""
			(at 257.81 222.25 0)
			(effects
				(font
					(size 1.27 1.27)
				)
				(hide yes)
			)
		)
		(property "MPN" "TXS0102DQER"
			(at 266.7 219.71 0)
			(effects
				(font
					(size 1.27 1.27)
					(thickness 0.15)
				)
			)
		)
		(property "Manufacturer" "Texas Instruments"
			(at 290.83 240.03 0)
			(effects
				(font
					(size 1.27 1.27)
					(thickness 0.15)
				)
				(justify left bottom)
				(hide yes)
			)
		)
		(property "Author" "Antmicro"
			(at 290.83 242.57 0)
			(effects
				(font
					(size 1.27 1.27)
					(thickness 0.15)
				)
				(justify left bottom)
				(hide yes)
			)
		)
		(property "License" "Apache-2.0"
			(at 290.83 245.11 0)
			(effects
				(font
					(size 1.27 1.27)
					(thickness 0.15)
				)
				(justify left bottom)
				(hide yes)
			)
		)
		(pin "2"
		)
		(pin "7"
		)
		(pin "5"
		)
		(pin "6"
		)
		(pin "8"
		)
		(pin "3"
		)
		(pin "4"
		)
		(pin "1"
		)
		(instances
			(project "data-center-rdimm-ddr5-tester"
				(path ""
					(reference "U32")
					(unit 1)
				)
			)
		)
	)
	(symbol
		(lib_id "antmicropower:GND")
		(at 78.74 90.17 0)
		(mirror y)
		(unit 1)
		(exclude_from_sim no)
		(in_bom yes)
		(on_board yes)
		(dnp no)
		(fields_autoplaced yes)
		(property "Reference" "#PWR0225"
			(at 78.74 96.52 0)
			(effects
				(font
					(size 1.27 1.27)
				)
				(hide yes)
			)
		)
		(property "Value" "GND"
			(at 80.645 94.615 0)
			(effects
				(font
					(size 1.27 1.27)
					(thickness 0.15)
				)
				(justify left bottom)
			)
		)
		(property "Footprint" ""
			(at 69.85 97.79 0)
			(effects
				(font
					(size 1.27 1.27)
					(thickness 0.15)
				)
				(justify left bottom)
				(hide yes)
			)
		)
		(property "Datasheet" ""
			(at 69.85 102.87 0)
			(effects
				(font
					(size 1.27 1.27)
					(thickness 0.15)
				)
				(justify left bottom)
				(hide yes)
			)
		)
		(property "Description" ""
			(at 78.74 90.17 0)
			(effects
				(font
					(size 1.27 1.27)
				)
				(hide yes)
			)
		)
		(property "Author" "Antmicro"
			(at 69.85 95.25 0)
			(effects
				(font
					(size 1.27 1.27)
					(thickness 0.15)
				)
				(justify left bottom)
				(hide yes)
			)
		)
		(property "License" "Apache-2.0"
			(at 69.85 97.79 0)
			(effects
				(font
					(size 1.27 1.27)
					(thickness 0.15)
				)
				(justify left bottom)
				(hide yes)
			)
		)
		(pin "1"
		)
		(instances
			(project "data-center-rdimm-ddr5-tester"
				(path ""
					(reference "#PWR0225")
					(unit 1)
				)
			)
		)
	)
	(symbol
		(lib_id "antmicropower:GND")
		(at 228.6 67.31 0)
		(mirror y)
		(unit 1)
		(exclude_from_sim no)
		(in_bom yes)
		(on_board yes)
		(dnp no)
		(property "Reference" "#PWR0213"
			(at 228.6 73.66 0)
			(effects
				(font
					(size 1.27 1.27)
				)
				(hide yes)
			)
		)
		(property "Value" "GND"
			(at 230.505 71.755 0)
			(effects
				(font
					(size 1.27 1.27)
					(thickness 0.15)
				)
				(justify left bottom)
			)
		)
		(property "Footprint" ""
			(at 219.71 74.93 0)
			(effects
				(font
					(size 1.27 1.27)
					(thickness 0.15)
				)
				(justify left bottom)
				(hide yes)
			)
		)
		(property "Datasheet" ""
			(at 219.71 80.01 0)
			(effects
				(font
					(size 1.27 1.27)
					(thickness 0.15)
				)
				(justify left bottom)
				(hide yes)
			)
		)
		(property "Description" ""
			(at 228.6 67.31 0)
			(effects
				(font
					(size 1.27 1.27)
				)
				(hide yes)
			)
		)
		(property "Author" "Antmicro"
			(at 219.71 72.39 0)
			(effects
				(font
					(size 1.27 1.27)
					(thickness 0.15)
				)
				(justify left bottom)
				(hide yes)
			)
		)
		(property "License" "Apache-2.0"
			(at 219.71 74.93 0)
			(effects
				(font
					(size 1.27 1.27)
					(thickness 0.15)
				)
				(justify left bottom)
				(hide yes)
			)
		)
		(pin "1"
		)
		(instances
			(project "data-center-rdimm-ddr5-tester"
				(path ""
					(reference "#PWR0213")
					(unit 1)
				)
			)
		)
	)
	(symbol
		(lib_id "antmicroCapacitors0402:C_100n_0402")
		(at 384.81 142.24 90)
		(unit 1)
		(exclude_from_sim no)
		(in_bom yes)
		(on_board yes)
		(dnp no)
		(fields_autoplaced yes)
		(property "Reference" "C124"
			(at 387.1341 138.863 90)
			(effects
				(font
					(size 1.27 1.27)
					(thickness 0.15)
				)
				(justify right)
			)
		)
		(property "Value" "C_100n_0402"
			(at 394.97 121.92 0)
			(effects
				(font
					(size 1.27 1.27)
					(thickness 0.15)
				)
				(justify left bottom)
				(hide yes)
			)
		)
		(property "Footprint" "antmicro-footprints:C_0402_1005Metric"
			(at 397.51 121.92 0)
			(effects
				(font
					(size 1.27 1.27)
					(thickness 0.15)
				)
				(justify left bottom)
				(hide yes)
			)
		)
		(property "Datasheet" "https://www.murata.com/products/productdetail?partno=GRM155R61H104KE14%23"
			(at 400.05 121.92 0)
			(effects
				(font
					(size 1.27 1.27)
					(thickness 0.15)
				)
				(justify left bottom)
				(hide yes)
			)
		)
		(property "Description" ""
			(at 384.81 142.24 0)
			(effects
				(font
					(size 1.27 1.27)
				)
				(hide yes)
			)
		)
		(property "MPN" "GRM155R61H104KE14D"
			(at 402.59 121.92 0)
			(effects
				(font
					(size 1.27 1.27)
					(thickness 0.15)
				)
				(justify left bottom)
				(hide yes)
			)
		)
		(property "Manufacturer" "Murata"
			(at 405.13 121.92 0)
			(effects
				(font
					(size 1.27 1.27)
					(thickness 0.15)
				)
				(justify left bottom)
				(hide yes)
			)
		)
		(property "License" "Apache-2.0"
			(at 407.67 121.92 0)
			(effects
				(font
					(size 1.27 1.27)
					(thickness 0.15)
				)
				(justify left bottom)
				(hide yes)
			)
		)
		(property "Author" "Antmicro"
			(at 410.21 121.92 0)
			(effects
				(font
					(size 1.27 1.27)
					(thickness 0.15)
				)
				(justify left bottom)
				(hide yes)
			)
		)
		(property "Val" "100n"
			(at 387.1341 141.3867 90)
			(effects
				(font
					(size 1.27 1.27)
					(thickness 0.15)
				)
				(justify right)
			)
		)
		(property "Voltage" "50V"
			(at 412.75 121.92 0)
			(effects
				(font
					(size 1.27 1.27)
				)
				(justify left bottom)
				(hide yes)
			)
		)
		(property "Dielectric" "X5R"
			(at 415.29 121.92 0)
			(effects
				(font
					(size 1.27 1.27)
				)
				(justify left bottom)
				(hide yes)
			)
		)
		(pin "1"
		)
		(pin "2"
		)
		(instances
			(project "data-center-rdimm-ddr5-tester"
				(path ""
					(reference "C124")
					(unit 1)
				)
			)
		)
	)
	(symbol
		(lib_id "antmicropower:GND")
		(at 81.28 46.99 90)
		(mirror x)
		(unit 1)
		(exclude_from_sim no)
		(in_bom yes)
		(on_board yes)
		(dnp no)
		(fields_autoplaced yes)
		(property "Reference" "#PWR0352"
			(at 87.63 46.99 0)
			(effects
				(font
					(size 1.27 1.27)
				)
				(hide yes)
			)
		)
		(property "Value" "GND"
			(at 85.725 45.085 0)
			(effects
				(font
					(size 1.27 1.27)
					(thickness 0.15)
				)
				(justify left bottom)
			)
		)
		(property "Footprint" ""
			(at 88.9 55.88 0)
			(effects
				(font
					(size 1.27 1.27)
					(thickness 0.15)
				)
				(justify left bottom)
				(hide yes)
			)
		)
		(property "Datasheet" ""
			(at 93.98 55.88 0)
			(effects
				(font
					(size 1.27 1.27)
					(thickness 0.15)
				)
				(justify left bottom)
				(hide yes)
			)
		)
		(property "Description" ""
			(at 81.28 46.99 0)
			(effects
				(font
					(size 1.27 1.27)
				)
				(hide yes)
			)
		)
		(property "Author" "Antmicro"
			(at 86.36 55.88 0)
			(effects
				(font
					(size 1.27 1.27)
					(thickness 0.15)
				)
				(justify left bottom)
				(hide yes)
			)
		)
		(property "License" "Apache-2.0"
			(at 88.9 55.88 0)
			(effects
				(font
					(size 1.27 1.27)
					(thickness 0.15)
				)
				(justify left bottom)
				(hide yes)
			)
		)
		(pin "1"
		)
		(instances
			(project "data-center-rdimm-ddr5-tester"
				(path ""
					(reference "#PWR0352")
					(unit 1)
				)
			)
		)
	)
	(symbol
		(lib_id "antmicroFerriteBeadsandChips:FB_600Z_0.5A_Murata-BLM18AG_0603")
		(at 44.45 148.59 0)
		(unit 1)
		(exclude_from_sim no)
		(in_bom yes)
		(on_board yes)
		(dnp no)
		(fields_autoplaced yes)
		(property "Reference" "FB2"
			(at 46.9519 143.195 0)
			(effects
				(font
					(size 1.27 1.27)
					(thickness 0.15)
				)
			)
		)
		(property "Value" "FB_600Z_0.5A_Murata-BLM18AG_0603"
			(at 59.69 151.13 0)
			(effects
				(font
					(size 1.27 1.27)
					(thickness 0.15)
				)
				(justify left bottom)
				(hide yes)
			)
		)
		(property "Footprint" "antmicro-footprints:FB_0603_1608Metric"
			(at 59.69 156.21 0)
			(effects
				(font
					(size 1.27 1.27)
					(thickness 0.15)
				)
				(justify left bottom)
				(hide yes)
			)
		)
		(property "Datasheet" "https://www.murata.com/en-us/products/productdata/8796738650142/ENFA0003.pdf"
			(at 59.69 158.75 0)
			(effects
				(font
					(size 1.27 1.27)
					(thickness 0.15)
				)
				(justify left bottom)
				(hide yes)
			)
		)
		(property "Description" ""
			(at 44.45 148.59 0)
			(effects
				(font
					(size 1.27 1.27)
				)
				(hide yes)
			)
		)
		(property "Val" "600Z/0.5A"
			(at 46.9519 145.7253 0)
			(effects
				(font
					(size 1.27 1.27)
				)
			)
		)
		(property "MPN" "BLM18AG601SN1D"
			(at 59.69 161.29 0)
			(effects
				(font
					(size 1.27 1.27)
					(thickness 0.15)
				)
				(justify left bottom)
				(hide yes)
			)
		)
		(property "Manufacturer" "Murata"
			(at 59.69 163.83 0)
			(effects
				(font
					(size 1.27 1.27)
					(thickness 0.15)
				)
				(justify left bottom)
				(hide yes)
			)
		)
		(property "Author" "Antmicro"
			(at 59.69 166.37 0)
			(effects
				(font
					(size 1.27 1.27)
					(thickness 0.15)
				)
				(justify left bottom)
				(hide yes)
			)
		)
		(property "License" "Apache-2.0"
			(at 59.69 168.91 0)
			(effects
				(font
					(size 1.27 1.27)
					(thickness 0.15)
				)
				(justify left bottom)
				(hide yes)
			)
		)
		(pin "1"
		)
		(pin "2"
		)
		(instances
			(project "data-center-rdimm-ddr5-tester"
				(path ""
					(reference "FB2")
					(unit 1)
				)
			)
		)
	)
	(symbol
		(lib_id "antmicropower:GND")
		(at 372.11 226.06 0)
		(unit 1)
		(exclude_from_sim no)
		(in_bom yes)
		(on_board yes)
		(dnp no)
		(property "Reference" "#PWR013"
			(at 372.11 232.41 0)
			(effects
				(font
					(size 1.27 1.27)
				)
				(hide yes)
			)
		)
		(property "Value" "GND"
			(at 370.205 230.505 0)
			(effects
				(font
					(size 1.27 1.27)
					(thickness 0.15)
				)
				(justify left bottom)
			)
		)
		(property "Footprint" ""
			(at 381 233.68 0)
			(effects
				(font
					(size 1.27 1.27)
					(thickness 0.15)
				)
				(justify left bottom)
				(hide yes)
			)
		)
		(property "Datasheet" ""
			(at 381 238.76 0)
			(effects
				(font
					(size 1.27 1.27)
					(thickness 0.15)
				)
				(justify left bottom)
				(hide yes)
			)
		)
		(property "Description" ""
			(at 372.11 226.06 0)
			(effects
				(font
					(size 1.27 1.27)
				)
				(hide yes)
			)
		)
		(property "Author" "Antmicro"
			(at 381 231.14 0)
			(effects
				(font
					(size 1.27 1.27)
					(thickness 0.15)
				)
				(justify left bottom)
				(hide yes)
			)
		)
		(property "License" "Apache-2.0"
			(at 381 233.68 0)
			(effects
				(font
					(size 1.27 1.27)
					(thickness 0.15)
				)
				(justify left bottom)
				(hide yes)
			)
		)
		(pin "1"
		)
		(instances
			(project "data-center-rdimm-ddr5-tester"
				(path ""
					(reference "#PWR013")
					(unit 1)
				)
			)
		)
	)
	(symbol
		(lib_id "antmicropower:+3V3")
		(at 384.81 198.12 0)
		(unit 1)
		(exclude_from_sim no)
		(in_bom yes)
		(on_board yes)
		(dnp no)
		(property "Reference" "#PWR014"
			(at 384.81 201.93 0)
			(effects
				(font
					(size 1.27 1.27)
				)
				(hide yes)
			)
		)
		(property "Value" "+3V3"
			(at 381.635 195.58 0)
			(effects
				(font
					(size 1.27 1.27)
					(thickness 0.15)
				)
				(justify left bottom)
			)
		)
		(property "Footprint" ""
			(at 400.05 205.74 0)
			(effects
				(font
					(size 1.27 1.27)
					(thickness 0.15)
				)
				(justify left bottom)
				(hide yes)
			)
		)
		(property "Datasheet" ""
			(at 400.05 208.28 0)
			(effects
				(font
					(size 1.27 1.27)
					(thickness 0.15)
				)
				(justify left bottom)
				(hide yes)
			)
		)
		(property "Description" ""
			(at 384.81 198.12 0)
			(effects
				(font
					(size 1.27 1.27)
				)
				(hide yes)
			)
		)
		(property "Author" "Antmicro"
			(at 400.05 200.66 0)
			(effects
				(font
					(size 1.27 1.27)
					(thickness 0.15)
				)
				(justify left bottom)
				(hide yes)
			)
		)
		(property "License" "Apache-2.0"
			(at 400.05 203.2 0)
			(effects
				(font
					(size 1.27 1.27)
					(thickness 0.15)
				)
				(justify left bottom)
				(hide yes)
			)
		)
		(pin "1"
		)
		(instances
			(project "data-center-rdimm-ddr5-tester"
				(path ""
					(reference "#PWR014")
					(unit 1)
				)
			)
		)
	)
	(symbol
		(lib_id "antmicroLogicTranslatorsLevelShifters:TXU0304BQAR")
		(at 257.81 165.1 0)
		(unit 1)
		(exclude_from_sim no)
		(in_bom yes)
		(on_board yes)
		(dnp no)
		(fields_autoplaced yes)
		(property "Reference" "U13"
			(at 266.7 158.115 0)
			(effects
				(font
					(size 1.27 1.27)
					(thickness 0.15)
				)
			)
		)
		(property "Value" "TXU0304BQAR"
			(at 289.56 167.64 0)
			(effects
				(font
					(size 1.27 1.27)
					(thickness 0.15)
				)
				(justify left bottom)
				(hide yes)
			)
		)
		(property "Footprint" "antmicro-footprints:DHVQFN-14-1EP_2.5x3mm"
			(at 289.56 170.18 0)
			(effects
				(font
					(size 1.27 1.27)
					(thickness 0.15)
				)
				(justify left bottom)
				(hide yes)
			)
		)
		(property "Datasheet" "https://www.ti.com/lit/ds/symlink/txu0304.pdf?ts=1637748643258&ref_url=https%253A%252F%252Fwww.ti.com%252Fproduct%252FTXU0304"
			(at 289.56 172.72 0)
			(effects
				(font
					(size 1.27 1.27)
					(thickness 0.15)
				)
				(justify left bottom)
				(hide yes)
			)
		)
		(property "Description" ""
			(at 257.81 165.1 0)
			(effects
				(font
					(size 1.27 1.27)
				)
				(hide yes)
			)
		)
		(property "MPN" "TXU0304BQAR"
			(at 266.7 160.655 0)
			(effects
				(font
					(size 1.27 1.27)
					(thickness 0.15)
				)
			)
		)
		(property "Manufacturer" "Texas Instruments"
			(at 289.56 177.8 0)
			(effects
				(font
					(size 1.27 1.27)
					(thickness 0.15)
				)
				(justify left bottom)
				(hide yes)
			)
		)
		(property "Author" "Antmicro"
			(at 289.56 180.34 0)
			(effects
				(font
					(size 1.27 1.27)
					(thickness 0.15)
				)
				(justify left bottom)
				(hide yes)
			)
		)
		(property "License" "Apache-2.0"
			(at 289.56 182.88 0)
			(effects
				(font
					(size 1.27 1.27)
					(thickness 0.15)
				)
				(justify left bottom)
				(hide yes)
			)
		)
		(pin "2"
		)
		(pin "11"
		)
		(pin "1"
		)
		(pin "14"
		)
		(pin "9"
		)
		(pin "6"
		)
		(pin "10"
		)
		(pin "5"
		)
		(pin "4"
		)
		(pin "8"
		)
		(pin "12"
		)
		(pin "3"
		)
		(pin "15"
		)
		(pin "7"
		)
		(pin "13"
		)
		(instances
			(project "data-center-rdimm-ddr5-tester"
				(path ""
					(reference "U13")
					(unit 1)
				)
			)
		)
	)
	(symbol
		(lib_id "antmicropower:GND")
		(at 332.74 83.82 0)
		(unit 1)
		(exclude_from_sim no)
		(in_bom yes)
		(on_board yes)
		(dnp no)
		(fields_autoplaced yes)
		(property "Reference" "#PWR0520"
			(at 332.74 90.17 0)
			(effects
				(font
					(size 1.27 1.27)
				)
				(hide yes)
			)
		)
		(property "Value" "GND"
			(at 330.835 88.265 0)
			(effects
				(font
					(size 1.27 1.27)
					(thickness 0.15)
				)
				(justify left bottom)
			)
		)
		(property "Footprint" ""
			(at 341.63 91.44 0)
			(effects
				(font
					(size 1.27 1.27)
					(thickness 0.15)
				)
				(justify left bottom)
				(hide yes)
			)
		)
		(property "Datasheet" ""
			(at 341.63 96.52 0)
			(effects
				(font
					(size 1.27 1.27)
					(thickness 0.15)
				)
				(justify left bottom)
				(hide yes)
			)
		)
		(property "Description" ""
			(at 332.74 83.82 0)
			(effects
				(font
					(size 1.27 1.27)
				)
				(hide yes)
			)
		)
		(property "Author" "Antmicro"
			(at 341.63 88.9 0)
			(effects
				(font
					(size 1.27 1.27)
					(thickness 0.15)
				)
				(justify left bottom)
				(hide yes)
			)
		)
		(property "License" "Apache-2.0"
			(at 341.63 91.44 0)
			(effects
				(font
					(size 1.27 1.27)
					(thickness 0.15)
				)
				(justify left bottom)
				(hide yes)
			)
		)
		(pin "1"
		)
		(instances
			(project "data-center-rdimm-ddr5-tester"
				(path ""
					(reference "#PWR0520")
					(unit 1)
				)
			)
		)
	)
	(symbol
		(lib_id "antmicroResistors0402:R_10k_0402")
		(at 191.77 246.38 90)
		(mirror x)
		(unit 1)
		(exclude_from_sim no)
		(in_bom yes)
		(on_board yes)
		(dnp no)
		(property "Reference" "R79"
			(at 193.04 247.65 90)
			(effects
				(font
					(size 1.27 1.27)
				)
				(justify right)
			)
		)
		(property "Value" "R_10k_0402"
			(at 204.47 266.7 0)
			(effects
				(font
					(size 1.27 1.27)
					(thickness 0.15)
				)
				(justify left bottom)
				(hide yes)
			)
		)
		(property "Footprint" "antmicro-footprints:R_0402_1005Metric"
			(at 207.01 266.7 0)
			(effects
				(font
					(size 1.27 1.27)
					(thickness 0.15)
				)
				(justify left bottom)
				(hide yes)
			)
		)
		(property "Datasheet" "https://www.bourns.com/docs/product-datasheets/cr.pdf"
			(at 209.55 266.7 0)
			(effects
				(font
					(size 1.27 1.27)
					(thickness 0.15)
				)
				(justify left bottom)
				(hide yes)
			)
		)
		(property "Description" ""
			(at 191.77 246.38 0)
			(effects
				(font
					(size 1.27 1.27)
				)
				(hide yes)
			)
		)
		(property "Manufacturer" "Bourns"
			(at 214.63 266.7 0)
			(effects
				(font
					(size 1.27 1.27)
					(thickness 0.15)
				)
				(justify left bottom)
				(hide yes)
			)
		)
		(property "MPN" "CR0402-FX-1002GLF"
			(at 212.09 266.7 0)
			(effects
				(font
					(size 1.27 1.27)
					(thickness 0.15)
				)
				(justify left bottom)
				(hide yes)
			)
		)
		(property "Val" "10k"
			(at 193.04 250.19 90)
			(effects
				(font
					(size 1.27 1.27)
					(thickness 0.15)
				)
				(justify right)
			)
		)
		(property "License" "Apache-2.0"
			(at 217.17 266.7 0)
			(effects
				(font
					(size 1.27 1.27)
					(thickness 0.15)
				)
				(justify left bottom)
				(hide yes)
			)
		)
		(property "Author" "Antmicro"
			(at 219.71 266.7 0)
			(effects
				(font
					(size 1.27 1.27)
					(thickness 0.15)
				)
				(justify left bottom)
				(hide yes)
			)
		)
		(property "Tolerance" "1%"
			(at 201.93 266.7 0)
			(effects
				(font
					(size 1.27 1.27)
				)
				(justify left bottom)
				(hide yes)
			)
		)
		(pin "1"
		)
		(pin "2"
		)
		(instances
			(project "data-center-rdimm-ddr5-tester"
				(path ""
					(reference "R79")
					(unit 1)
				)
			)
		)
	)
	(symbol
		(lib_id "antmicropower:GND")
		(at 200.66 252.73 0)
		(unit 1)
		(exclude_from_sim no)
		(in_bom yes)
		(on_board yes)
		(dnp no)
		(property "Reference" "#PWR0215"
			(at 200.66 259.08 0)
			(effects
				(font
					(size 1.27 1.27)
				)
				(hide yes)
			)
		)
		(property "Value" "GND"
			(at 198.755 257.175 0)
			(effects
				(font
					(size 1.27 1.27)
					(thickness 0.15)
				)
				(justify left bottom)
			)
		)
		(property "Footprint" ""
			(at 209.55 260.35 0)
			(effects
				(font
					(size 1.27 1.27)
					(thickness 0.15)
				)
				(justify left bottom)
				(hide yes)
			)
		)
		(property "Datasheet" ""
			(at 209.55 265.43 0)
			(effects
				(font
					(size 1.27 1.27)
					(thickness 0.15)
				)
				(justify left bottom)
				(hide yes)
			)
		)
		(property "Description" ""
			(at 200.66 252.73 0)
			(effects
				(font
					(size 1.27 1.27)
				)
				(hide yes)
			)
		)
		(property "Author" "Antmicro"
			(at 209.55 257.81 0)
			(effects
				(font
					(size 1.27 1.27)
					(thickness 0.15)
				)
				(justify left bottom)
				(hide yes)
			)
		)
		(property "License" "Apache-2.0"
			(at 209.55 260.35 0)
			(effects
				(font
					(size 1.27 1.27)
					(thickness 0.15)
				)
				(justify left bottom)
				(hide yes)
			)
		)
		(pin "1"
		)
		(instances
			(project "data-center-rdimm-ddr5-tester"
				(path ""
					(reference "#PWR0215")
					(unit 1)
				)
			)
		)
	)
	(symbol
		(lib_id "antmicroCoaxialConnectorsRF:U_FL-R-SMT-1")
		(at 373.38 41.91 0)
		(unit 1)
		(exclude_from_sim no)
		(in_bom yes)
		(on_board yes)
		(dnp no)
		(property "Reference" "J13"
			(at 379.095 34.925 0)
			(effects
				(font
					(size 1.27 1.27)
					(thickness 0.15)
				)
				(justify left)
			)
		)
		(property "Value" "U_FL-R-SMT-1"
			(at 393.7 49.53 0)
			(effects
				(font
					(size 1.27 1.27)
					(thickness 0.15)
				)
				(justify left bottom)
				(hide yes)
			)
		)
		(property "Footprint" "antmicro-footprints:Coax_Conn_U.FL"
			(at 393.7 52.07 0)
			(effects
				(font
					(size 1.27 1.27)
					(thickness 0.15)
				)
				(justify left bottom)
				(hide yes)
			)
		)
		(property "Datasheet" "https://media.digikey.com/pdf/Data%20Sheets/Hirose%20PDFs/UFL%20Series.pdf"
			(at 393.7 54.61 0)
			(effects
				(font
					(size 1.27 1.27)
					(thickness 0.15)
				)
				(justify left bottom)
				(hide yes)
			)
		)
		(property "Description" ""
			(at 373.38 41.91 0)
			(effects
				(font
					(size 1.27 1.27)
				)
				(hide yes)
			)
		)
		(property "MPN" "U.FL-R-SMT-1(10)"
			(at 371.475 38.1 0)
			(effects
				(font
					(size 1.27 1.27)
					(thickness 0.15)
				)
				(justify left)
			)
		)
		(property "Manufacturer" "Hirose Electric"
			(at 393.7 57.15 0)
			(effects
				(font
					(size 1.27 1.27)
					(thickness 0.15)
				)
				(justify left bottom)
				(hide yes)
			)
		)
		(property "Author" "Antmicro"
			(at 393.7 59.69 0)
			(effects
				(font
					(size 1.27 1.27)
					(thickness 0.15)
				)
				(justify left bottom)
				(hide yes)
			)
		)
		(property "License" "Apache-2.0"
			(at 393.7 62.23 0)
			(effects
				(font
					(size 1.27 1.27)
					(thickness 0.15)
				)
				(justify left bottom)
				(hide yes)
			)
		)
		(pin "SH2"
		)
		(pin "SH1"
		)
		(pin "1"
		)
		(instances
			(project "data-center-rdimm-ddr5-tester"
				(path ""
					(reference "J13")
					(unit 1)
				)
			)
		)
	)
	(symbol
		(lib_id "antmicroResistors0402:R_330R_0402")
		(at 134.62 259.08 0)
		(unit 1)
		(exclude_from_sim no)
		(in_bom yes)
		(on_board yes)
		(dnp no)
		(property "Reference" "R64"
			(at 139.7 259.08 0)
			(effects
				(font
					(size 1.27 1.27)
				)
				(justify left bottom)
			)
		)
		(property "Value" "R_330R_0402"
			(at 154.94 271.78 0)
			(effects
				(font
					(size 1.27 1.27)
					(thickness 0.15)
				)
				(justify left bottom)
				(hide yes)
			)
		)
		(property "Footprint" "antmicro-footprints:R_0402_1005Metric"
			(at 154.94 274.32 0)
			(effects
				(font
					(size 1.27 1.27)
					(thickness 0.15)
				)
				(justify left bottom)
				(hide yes)
			)
		)
		(property "Datasheet" "https://www.bourns.com/docs/product-datasheets/cr.pdf"
			(at 154.94 276.86 0)
			(effects
				(font
					(size 1.27 1.27)
					(thickness 0.15)
				)
				(justify left bottom)
				(hide yes)
			)
		)
		(property "Description" ""
			(at 134.62 259.08 0)
			(effects
				(font
					(size 1.27 1.27)
				)
				(hide yes)
			)
		)
		(property "Manufacturer" "Bourns"
			(at 154.94 281.94 0)
			(effects
				(font
					(size 1.27 1.27)
					(thickness 0.15)
				)
				(justify left bottom)
				(hide yes)
			)
		)
		(property "MPN" "CR0402-FX-3300GLF"
			(at 154.94 279.4 0)
			(effects
				(font
					(size 1.27 1.27)
					(thickness 0.15)
				)
				(justify left bottom)
				(hide yes)
			)
		)
		(property "Val" "330R"
			(at 129.54 259.08 0)
			(effects
				(font
					(size 1.27 1.27)
					(thickness 0.15)
				)
				(justify left bottom)
			)
		)
		(property "License" "Apache-2.0"
			(at 154.94 284.48 0)
			(effects
				(font
					(size 1.27 1.27)
					(thickness 0.15)
				)
				(justify left bottom)
				(hide yes)
			)
		)
		(property "Author" "Antmicro"
			(at 154.94 287.02 0)
			(effects
				(font
					(size 1.27 1.27)
					(thickness 0.15)
				)
				(justify left bottom)
				(hide yes)
			)
		)
		(property "Tolerance" "1%"
			(at 154.94 269.24 0)
			(effects
				(font
					(size 1.27 1.27)
				)
				(justify left bottom)
				(hide yes)
			)
		)
		(pin "1"
		)
		(pin "2"
		)
		(instances
			(project "data-center-rdimm-ddr5-tester"
				(path ""
					(reference "R64")
					(unit 1)
				)
			)
		)
	)
	(symbol
		(lib_id "antmicropower:GND")
		(at 60.96 156.21 0)
		(unit 1)
		(exclude_from_sim no)
		(in_bom yes)
		(on_board yes)
		(dnp no)
		(fields_autoplaced yes)
		(property "Reference" "#PWR0248"
			(at 60.96 162.56 0)
			(effects
				(font
					(size 1.27 1.27)
				)
				(hide yes)
			)
		)
		(property "Value" "GND"
			(at 59.055 160.655 0)
			(effects
				(font
					(size 1.27 1.27)
					(thickness 0.15)
				)
				(justify left bottom)
			)
		)
		(property "Footprint" ""
			(at 69.85 163.83 0)
			(effects
				(font
					(size 1.27 1.27)
					(thickness 0.15)
				)
				(justify left bottom)
				(hide yes)
			)
		)
		(property "Datasheet" ""
			(at 69.85 168.91 0)
			(effects
				(font
					(size 1.27 1.27)
					(thickness 0.15)
				)
				(justify left bottom)
				(hide yes)
			)
		)
		(property "Description" ""
			(at 60.96 156.21 0)
			(effects
				(font
					(size 1.27 1.27)
				)
				(hide yes)
			)
		)
		(property "Author" "Antmicro"
			(at 69.85 161.29 0)
			(effects
				(font
					(size 1.27 1.27)
					(thickness 0.15)
				)
				(justify left bottom)
				(hide yes)
			)
		)
		(property "License" "Apache-2.0"
			(at 69.85 163.83 0)
			(effects
				(font
					(size 1.27 1.27)
					(thickness 0.15)
				)
				(justify left bottom)
				(hide yes)
			)
		)
		(pin "1"
		)
		(instances
			(project "data-center-rdimm-ddr5-tester"
				(path ""
					(reference "#PWR0248")
					(unit 1)
				)
			)
		)
	)
	(symbol
		(lib_id "antmicroTestPoints:TP_1mm_SMD")
		(at 95.25 39.37 0)
		(mirror x)
		(unit 1)
		(exclude_from_sim no)
		(in_bom no)
		(on_board yes)
		(dnp no)
		(property "Reference" "TP22"
			(at 99.695 37.465 0)
			(effects
				(font
					(size 1.27 1.27)
				)
			)
		)
		(property "Value" "TP_1mm_SMD"
			(at 110.49 31.75 0)
			(effects
				(font
					(size 1.27 1.27)
					(thickness 0.15)
				)
				(justify left bottom)
				(hide yes)
			)
		)
		(property "Footprint" "antmicro-footprints:TP_SMD_1mm"
			(at 110.49 29.21 0)
			(effects
				(font
					(size 1.27 1.27)
					(thickness 0.15)
				)
				(justify left bottom)
				(hide yes)
			)
		)
		(property "Datasheet" ""
			(at 110.49 26.67 0)
			(effects
				(font
					(size 1.27 1.27)
					(thickness 0.15)
				)
				(justify left bottom)
				(hide yes)
			)
		)
		(property "Description" ""
			(at 95.25 39.37 0)
			(effects
				(font
					(size 1.27 1.27)
				)
				(hide yes)
			)
		)
		(property "MPN" ""
			(at 95.25 39.37 0)
			(effects
				(font
					(size 1.27 1.27)
				)
				(hide yes)
			)
		)
		(property "Manufacturer" ""
			(at 95.25 39.37 0)
			(effects
				(font
					(size 1.27 1.27)
				)
				(hide yes)
			)
		)
		(property "Author" "Antmicro"
			(at 110.49 24.13 0)
			(effects
				(font
					(size 1.27 1.27)
					(thickness 0.15)
				)
				(justify left bottom)
				(hide yes)
			)
		)
		(property "License" "Apache-2.0"
			(at 110.49 21.59 0)
			(effects
				(font
					(size 1.27 1.27)
					(thickness 0.15)
				)
				(justify left bottom)
				(hide yes)
			)
		)
		(pin "1"
		)
		(instances
			(project "data-center-rdimm-ddr5-tester"
				(path ""
					(reference "TP22")
					(unit 1)
				)
			)
		)
	)
	(symbol
		(lib_id "antmicroTransistorsFETsMOSFETsSingle:BSS84AKW")
		(at 261.62 48.26 0)
		(mirror x)
		(unit 1)
		(exclude_from_sim no)
		(in_bom yes)
		(on_board yes)
		(dnp no)
		(property "Reference" "Q20"
			(at 272.415 49.53 0)
			(effects
				(font
					(size 1.27 1.27)
					(thickness 0.15)
				)
				(justify left)
			)
		)
		(property "Value" "BSS84AKW"
			(at 284.48 40.64 0)
			(effects
				(font
					(size 1.27 1.27)
					(thickness 0.15)
				)
				(justify left bottom)
				(hide yes)
			)
		)
		(property "Footprint" "antmicro-footprints:SOT-323"
			(at 284.48 38.1 0)
			(effects
				(font
					(size 1.27 1.27)
					(thickness 0.15)
				)
				(justify left bottom)
				(hide yes)
			)
		)
		(property "Datasheet" "https://assets.nexperia.com/documents/data-sheet/BSS84AKW.pdf"
			(at 284.48 35.56 0)
			(effects
				(font
					(size 1.27 1.27)
					(thickness 0.15)
				)
				(justify left bottom)
				(hide yes)
			)
		)
		(property "Description" ""
			(at 261.62 48.26 0)
			(effects
				(font
					(size 1.27 1.27)
				)
				(hide yes)
			)
		)
		(property "MPN" "BSS84AKW,115"
			(at 272.415 52.07 0)
			(effects
				(font
					(size 1.27 1.27)
					(thickness 0.15)
				)
				(justify left)
			)
		)
		(property "Manufacturer" "Nexperia"
			(at 284.48 33.02 0)
			(effects
				(font
					(size 1.27 1.27)
					(thickness 0.15)
				)
				(justify left bottom)
				(hide yes)
			)
		)
		(property "Author" "Antmicro"
			(at 284.48 30.48 0)
			(effects
				(font
					(size 1.27 1.27)
					(thickness 0.15)
				)
				(justify left bottom)
				(hide yes)
			)
		)
		(property "License" "Apache-2.0"
			(at 284.48 27.94 0)
			(effects
				(font
					(size 1.27 1.27)
					(thickness 0.15)
				)
				(justify left bottom)
				(hide yes)
			)
		)
		(pin "1"
		)
		(pin "3"
		)
		(pin "2"
		)
		(instances
			(project "data-center-rdimm-ddr5-tester"
				(path ""
					(reference "Q20")
					(unit 1)
				)
			)
		)
	)
	(symbol
		(lib_id "antmicropower:+3V3")
		(at 278.13 222.25 0)
		(unit 1)
		(exclude_from_sim no)
		(in_bom yes)
		(on_board yes)
		(dnp no)
		(property "Reference" "#PWR011"
			(at 278.13 226.06 0)
			(effects
				(font
					(size 1.27 1.27)
				)
				(hide yes)
			)
		)
		(property "Value" "+3V3"
			(at 274.955 219.71 0)
			(effects
				(font
					(size 1.27 1.27)
					(thickness 0.15)
				)
				(justify left bottom)
			)
		)
		(property "Footprint" ""
			(at 293.37 229.87 0)
			(effects
				(font
					(size 1.27 1.27)
					(thickness 0.15)
				)
				(justify left bottom)
				(hide yes)
			)
		)
		(property "Datasheet" ""
			(at 293.37 232.41 0)
			(effects
				(font
					(size 1.27 1.27)
					(thickness 0.15)
				)
				(justify left bottom)
				(hide yes)
			)
		)
		(property "Description" ""
			(at 278.13 222.25 0)
			(effects
				(font
					(size 1.27 1.27)
				)
				(hide yes)
			)
		)
		(property "Author" "Antmicro"
			(at 293.37 224.79 0)
			(effects
				(font
					(size 1.27 1.27)
					(thickness 0.15)
				)
				(justify left bottom)
				(hide yes)
			)
		)
		(property "License" "Apache-2.0"
			(at 293.37 227.33 0)
			(effects
				(font
					(size 1.27 1.27)
					(thickness 0.15)
				)
				(justify left bottom)
				(hide yes)
			)
		)
		(pin "1"
		)
		(instances
			(project "data-center-rdimm-ddr5-tester"
				(path ""
					(reference "#PWR011")
					(unit 1)
				)
			)
		)
	)
	(symbol
		(lib_id "antmicroResistors0402:R_4k7_0402")
		(at 320.04 161.29 270)
		(unit 1)
		(exclude_from_sim no)
		(in_bom yes)
		(on_board yes)
		(dnp no)
		(property "Reference" "R94"
			(at 318.77 162.56 90)
			(effects
				(font
					(size 1.27 1.27)
				)
				(justify right)
			)
		)
		(property "Value" "R_4k7_0402"
			(at 307.34 181.61 0)
			(effects
				(font
					(size 1.27 1.27)
					(thickness 0.15)
				)
				(justify left bottom)
				(hide yes)
			)
		)
		(property "Footprint" "antmicro-footprints:R_0402_1005Metric"
			(at 304.8 181.61 0)
			(effects
				(font
					(size 1.27 1.27)
					(thickness 0.15)
				)
				(justify left bottom)
				(hide yes)
			)
		)
		(property "Datasheet" "https://www.bourns.com/docs/product-datasheets/cr.pdf"
			(at 302.26 181.61 0)
			(effects
				(font
					(size 1.27 1.27)
					(thickness 0.15)
				)
				(justify left bottom)
				(hide yes)
			)
		)
		(property "Description" ""
			(at 320.04 161.29 0)
			(effects
				(font
					(size 1.27 1.27)
				)
				(hide yes)
			)
		)
		(property "Manufacturer" "Bourns"
			(at 297.18 181.61 0)
			(effects
				(font
					(size 1.27 1.27)
					(thickness 0.15)
				)
				(justify left bottom)
				(hide yes)
			)
		)
		(property "MPN" "CR0402-FX-4701GLF"
			(at 299.72 181.61 0)
			(effects
				(font
					(size 1.27 1.27)
					(thickness 0.15)
				)
				(justify left bottom)
				(hide yes)
			)
		)
		(property "Val" "4k7"
			(at 318.77 165.735 90)
			(effects
				(font
					(size 1.27 1.27)
					(thickness 0.15)
				)
				(justify right)
			)
		)
		(property "License" "Apache-2.0"
			(at 294.64 181.61 0)
			(effects
				(font
					(size 1.27 1.27)
					(thickness 0.15)
				)
				(justify left bottom)
				(hide yes)
			)
		)
		(property "Author" "Antmicro"
			(at 292.1 181.61 0)
			(effects
				(font
					(size 1.27 1.27)
					(thickness 0.15)
				)
				(justify left bottom)
				(hide yes)
			)
		)
		(property "Tolerance" "1%"
			(at 309.88 181.61 0)
			(effects
				(font
					(size 1.27 1.27)
				)
				(justify left bottom)
				(hide yes)
			)
		)
		(pin "1"
		)
		(pin "2"
		)
		(instances
			(project "data-center-rdimm-ddr5-tester"
				(path ""
					(reference "R94")
					(unit 1)
				)
			)
		)
	)
	(symbol
		(lib_id "antmicroCoaxialConnectorsRF:U_FL-R-SMT-1")
		(at 322.58 41.91 0)
		(unit 1)
		(exclude_from_sim no)
		(in_bom yes)
		(on_board yes)
		(dnp no)
		(property "Reference" "J9"
			(at 328.295 34.925 0)
			(effects
				(font
					(size 1.27 1.27)
					(thickness 0.15)
				)
				(justify left)
			)
		)
		(property "Value" "U_FL-R-SMT-1"
			(at 342.9 49.53 0)
			(effects
				(font
					(size 1.27 1.27)
					(thickness 0.15)
				)
				(justify left bottom)
				(hide yes)
			)
		)
		(property "Footprint" "antmicro-footprints:Coax_Conn_U.FL"
			(at 342.9 52.07 0)
			(effects
				(font
					(size 1.27 1.27)
					(thickness 0.15)
				)
				(justify left bottom)
				(hide yes)
			)
		)
		(property "Datasheet" "https://media.digikey.com/pdf/Data%20Sheets/Hirose%20PDFs/UFL%20Series.pdf"
			(at 342.9 54.61 0)
			(effects
				(font
					(size 1.27 1.27)
					(thickness 0.15)
				)
				(justify left bottom)
				(hide yes)
			)
		)
		(property "Description" ""
			(at 322.58 41.91 0)
			(effects
				(font
					(size 1.27 1.27)
				)
				(hide yes)
			)
		)
		(property "MPN" "U.FL-R-SMT-1(10)"
			(at 320.04 38.1 0)
			(effects
				(font
					(size 1.27 1.27)
					(thickness 0.15)
				)
				(justify left)
			)
		)
		(property "Manufacturer" "Hirose Electric"
			(at 342.9 57.15 0)
			(effects
				(font
					(size 1.27 1.27)
					(thickness 0.15)
				)
				(justify left bottom)
				(hide yes)
			)
		)
		(property "Author" "Antmicro"
			(at 342.9 59.69 0)
			(effects
				(font
					(size 1.27 1.27)
					(thickness 0.15)
				)
				(justify left bottom)
				(hide yes)
			)
		)
		(property "License" "Apache-2.0"
			(at 342.9 62.23 0)
			(effects
				(font
					(size 1.27 1.27)
					(thickness 0.15)
				)
				(justify left bottom)
				(hide yes)
			)
		)
		(pin "SH2"
		)
		(pin "SH1"
		)
		(pin "1"
		)
		(instances
			(project "data-center-rdimm-ddr5-tester"
				(path ""
					(reference "J9")
					(unit 1)
				)
			)
		)
	)
	(symbol
		(lib_id "antmicroLEDIndicationDiscrete:LED_G_0603_KP-1608CGCK")
		(at 116.84 265.43 0)
		(unit 1)
		(exclude_from_sim no)
		(in_bom yes)
		(on_board yes)
		(dnp no)
		(property "Reference" "D12"
			(at 123.825 264.16 0)
			(effects
				(font
					(size 1.27 1.27)
					(thickness 0.15)
				)
			)
		)
		(property "Value" "LED_G_0603_KP-1608CGCK"
			(at 139.7 273.05 0)
			(effects
				(font
					(size 1.27 1.27)
					(thickness 0.15)
				)
				(justify left bottom)
				(hide yes)
			)
		)
		(property "Footprint" "antmicro-footprints:LED_0603_1608Metric_G"
			(at 139.7 275.59 0)
			(effects
				(font
					(size 1.27 1.27)
					(thickness 0.15)
				)
				(justify left bottom)
				(hide yes)
			)
		)
		(property "Datasheet" "http://www.kingbright.com/attachments/file/psearch//000/00/00/KP-1608CGCK(Ver.23B).pdf"
			(at 139.7 278.13 0)
			(effects
				(font
					(size 1.27 1.27)
					(thickness 0.15)
				)
				(justify left bottom)
				(hide yes)
			)
		)
		(property "Description" ""
			(at 116.84 265.43 0)
			(effects
				(font
					(size 1.27 1.27)
				)
				(hide yes)
			)
		)
		(property "MPN" "KP-1608CGCK"
			(at 119.38 261.62 0)
			(effects
				(font
					(size 1.27 1.27)
					(thickness 0.15)
				)
			)
		)
		(property "Manufacturer" "Kingbright"
			(at 139.7 283.21 0)
			(effects
				(font
					(size 1.27 1.27)
					(thickness 0.15)
				)
				(justify left bottom)
				(hide yes)
			)
		)
		(property "Color" "Green"
			(at 114.935 264.16 0)
			(effects
				(font
					(size 1.27 1.27)
				)
			)
		)
		(property "Author" "Antmicro"
			(at 139.7 285.75 0)
			(effects
				(font
					(size 1.27 1.27)
					(thickness 0.15)
				)
				(justify left bottom)
				(hide yes)
			)
		)
		(property "License" "Apache-2.0"
			(at 139.7 288.29 0)
			(effects
				(font
					(size 1.27 1.27)
					(thickness 0.15)
				)
				(justify left bottom)
				(hide yes)
			)
		)
		(pin "1"
		)
		(pin "2"
		)
		(instances
			(project "data-center-rdimm-ddr5-tester"
				(path ""
					(reference "D12")
					(unit 1)
				)
			)
		)
	)
	(symbol
		(lib_id "antmicropower:GND")
		(at 372.11 167.64 0)
		(unit 1)
		(exclude_from_sim no)
		(in_bom yes)
		(on_board yes)
		(dnp no)
		(property "Reference" "#PWR0200"
			(at 372.11 173.99 0)
			(effects
				(font
					(size 1.27 1.27)
				)
				(hide yes)
			)
		)
		(property "Value" "GND"
			(at 370.205 172.085 0)
			(effects
				(font
					(size 1.27 1.27)
					(thickness 0.15)
				)
				(justify left bottom)
			)
		)
		(property "Footprint" ""
			(at 381 175.26 0)
			(effects
				(font
					(size 1.27 1.27)
					(thickness 0.15)
				)
				(justify left bottom)
				(hide yes)
			)
		)
		(property "Datasheet" ""
			(at 381 180.34 0)
			(effects
				(font
					(size 1.27 1.27)
					(thickness 0.15)
				)
				(justify left bottom)
				(hide yes)
			)
		)
		(property "Description" ""
			(at 372.11 167.64 0)
			(effects
				(font
					(size 1.27 1.27)
				)
				(hide yes)
			)
		)
		(property "Author" "Antmicro"
			(at 381 172.72 0)
			(effects
				(font
					(size 1.27 1.27)
					(thickness 0.15)
				)
				(justify left bottom)
				(hide yes)
			)
		)
		(property "License" "Apache-2.0"
			(at 381 175.26 0)
			(effects
				(font
					(size 1.27 1.27)
					(thickness 0.15)
				)
				(justify left bottom)
				(hide yes)
			)
		)
		(pin "1"
		)
		(instances
			(project "data-center-rdimm-ddr5-tester"
				(path ""
					(reference "#PWR0200")
					(unit 1)
				)
			)
		)
	)
	(symbol
		(lib_id "antmicroPMICVoltageRegulatorsLinear:NCP718BSN330T1G")
		(at 207.01 57.15 0)
		(unit 1)
		(exclude_from_sim no)
		(in_bom yes)
		(on_board yes)
		(dnp no)
		(fields_autoplaced yes)
		(property "Reference" "U5"
			(at 217.17 49.53 0)
			(effects
				(font
					(size 1.27 1.27)
					(thickness 0.15)
				)
			)
		)
		(property "Value" "NCP718BSN330T1G"
			(at 242.57 63.5 0)
			(effects
				(font
					(size 1.27 1.27)
					(thickness 0.15)
				)
				(justify left bottom)
				(hide yes)
			)
		)
		(property "Footprint" "antmicro-footprints:SOT-23-5"
			(at 242.57 66.04 0)
			(effects
				(font
					(size 1.27 1.27)
					(thickness 0.15)
				)
				(justify left bottom)
				(hide yes)
			)
		)
		(property "Datasheet" "https://www.mouser.com/datasheet/2/308/NCP718_D-1224359.pdf"
			(at 242.57 68.58 0)
			(effects
				(font
					(size 1.27 1.27)
					(thickness 0.15)
				)
				(justify left bottom)
				(hide yes)
			)
		)
		(property "Description" ""
			(at 207.01 57.15 0)
			(effects
				(font
					(size 1.27 1.27)
				)
				(hide yes)
			)
		)
		(property "MPN" "NCP718BSN330T1G"
			(at 217.17 52.07 0)
			(effects
				(font
					(size 1.27 1.27)
					(thickness 0.15)
				)
			)
		)
		(property "Manufacturer" "ON Semiconductor"
			(at 242.57 73.66 0)
			(effects
				(font
					(size 1.27 1.27)
					(thickness 0.15)
				)
				(justify left bottom)
				(hide yes)
			)
		)
		(property "Author" "Antmicro"
			(at 242.57 76.2 0)
			(effects
				(font
					(size 1.27 1.27)
					(thickness 0.15)
				)
				(justify left bottom)
				(hide yes)
			)
		)
		(property "License" "Apache-2.0"
			(at 242.57 78.74 0)
			(effects
				(font
					(size 1.27 1.27)
					(thickness 0.15)
				)
				(justify left bottom)
				(hide yes)
			)
		)
		(pin "3"
		)
		(pin "5"
		)
		(pin "2"
		)
		(pin "1"
		)
		(pin "4"
		)
		(instances
			(project "data-center-rdimm-ddr5-tester"
				(path ""
					(reference "U5")
					(unit 1)
				)
			)
		)
	)
	(symbol
		(lib_id "antmicropower:PWR_FLAG")
		(at 59.69 167.64 0)
		(unit 1)
		(exclude_from_sim no)
		(in_bom yes)
		(on_board yes)
		(dnp no)
		(fields_autoplaced yes)
		(property "Reference" "#FLG0102"
			(at 59.69 165.735 0)
			(effects
				(font
					(size 1.27 1.27)
				)
				(hide yes)
			)
		)
		(property "Value" "PWR_FLAG"
			(at 59.69 164.0642 0)
			(effects
				(font
					(size 1.27 1.27)
				)
			)
		)
		(property "Footprint" ""
			(at 59.69 167.64 0)
			(effects
				(font
					(size 1.27 1.27)
				)
				(hide yes)
			)
		)
		(property "Datasheet" ""
			(at 59.69 167.64 0)
			(effects
				(font
					(size 1.27 1.27)
				)
				(hide yes)
			)
		)
		(property "Description" ""
			(at 59.69 167.64 0)
			(effects
				(font
					(size 1.27 1.27)
				)
				(hide yes)
			)
		)
		(pin "1"
		)
		(instances
			(project "data-center-rdimm-ddr5-tester"
				(path ""
					(reference "#FLG0102")
					(unit 1)
				)
			)
		)
	)
	(symbol
		(lib_id "antmicroInterfaceControllers:FT4232H_VQFN")
		(at 105.41 125.73 0)
		(unit 1)
		(exclude_from_sim no)
		(in_bom yes)
		(on_board yes)
		(dnp no)
		(fields_autoplaced yes)
		(property "Reference" "U6"
			(at 125.73 118.11 0)
			(effects
				(font
					(size 1.27 1.27)
					(thickness 0.15)
				)
			)
		)
		(property "Value" "FT4232H_VQFN"
			(at 161.29 140.97 0)
			(effects
				(font
					(size 1.27 1.27)
					(thickness 0.15)
				)
				(justify left bottom)
				(hide yes)
			)
		)
		(property "Footprint" "antmicro-footprints:QFN-56-1EP_8x8mm_P0.5mm"
			(at 161.29 133.35 0)
			(effects
				(font
					(size 1.27 1.27)
					(thickness 0.15)
				)
				(justify left bottom)
				(hide yes)
			)
		)
		(property "Datasheet" "https://www.ftdichip.com/Support/Documents/DataSheets/ICs/DS_FT4232H.pdf"
			(at 161.29 135.89 0)
			(effects
				(font
					(size 1.27 1.27)
					(thickness 0.15)
				)
				(justify left bottom)
				(hide yes)
			)
		)
		(property "Description" ""
			(at 105.41 125.73 0)
			(effects
				(font
					(size 1.27 1.27)
				)
				(hide yes)
			)
		)
		(property "Manufacturer" "FTDI Chip"
			(at 161.29 138.43 0)
			(effects
				(font
					(size 1.27 1.27)
					(thickness 0.15)
				)
				(justify left bottom)
				(hide yes)
			)
		)
		(property "MPN" "FT4232H-56Q-REEL"
			(at 125.73 120.65 0)
			(effects
				(font
					(size 1.27 1.27)
					(thickness 0.15)
				)
			)
		)
		(property "Author" "Antmicro"
			(at 161.29 143.51 0)
			(effects
				(font
					(size 1.27 1.27)
					(thickness 0.15)
				)
				(justify left bottom)
				(hide yes)
			)
		)
		(property "License" "Apache-2.0"
			(at 161.29 146.05 0)
			(effects
				(font
					(size 1.27 1.27)
					(thickness 0.15)
				)
				(justify left bottom)
				(hide yes)
			)
		)
		(pin "26"
		)
		(pin "20"
		)
		(pin "33"
		)
		(pin "57"
		)
		(pin "52"
		)
		(pin "2"
		)
		(pin "7"
		)
		(pin "40"
		)
		(pin "29"
		)
		(pin "56"
		)
		(pin "21"
		)
		(pin "50"
		)
		(pin "6"
		)
		(pin "34"
		)
		(pin "8"
		)
		(pin "5"
		)
		(pin "48"
		)
		(pin "31"
		)
		(pin "47"
		)
		(pin "23"
		)
		(pin "38"
		)
		(pin "45"
		)
		(pin "28"
		)
		(pin "3"
		)
		(pin "9"
		)
		(pin "54"
		)
		(pin "17"
		)
		(pin "32"
		)
		(pin "49"
		)
		(pin "51"
		)
		(pin "15"
		)
		(pin "35"
		)
		(pin "43"
		)
		(pin "39"
		)
		(pin "16"
		)
		(pin "24"
		)
		(pin "25"
		)
		(pin "10"
		)
		(pin "42"
		)
		(pin "41"
		)
		(pin "55"
		)
		(pin "4"
		)
		(pin "19"
		)
		(pin "1"
		)
		(pin "18"
		)
		(pin "30"
		)
		(pin "37"
		)
		(pin "11"
		)
		(pin "53"
		)
		(pin "27"
		)
		(pin "36"
		)
		(pin "13"
		)
		(pin "44"
		)
		(pin "22"
		)
		(pin "46"
		)
		(pin "12"
		)
		(pin "14"
		)
		(instances
			(project "data-center-rdimm-ddr5-tester"
				(path ""
					(reference "U6")
					(unit 1)
				)
			)
		)
	)
	(symbol
		(lib_id "antmicropower:+1V8")
		(at 280.67 129.54 0)
		(unit 1)
		(exclude_from_sim no)
		(in_bom yes)
		(on_board yes)
		(dnp no)
		(fields_autoplaced yes)
		(property "Reference" "#PWR0192"
			(at 295.91 132.08 0)
			(effects
				(font
					(size 1.27 1.27)
					(thickness 0.15)
				)
				(justify left bottom)
				(hide yes)
			)
		)
		(property "Value" "+1V8"
			(at 280.67 124.46 0)
			(effects
				(font
					(size 1.27 1.27)
					(thickness 0.15)
				)
			)
		)
		(property "Footprint" ""
			(at 295.91 137.16 0)
			(effects
				(font
					(size 1.27 1.27)
					(thickness 0.15)
				)
				(justify left bottom)
				(hide yes)
			)
		)
		(property "Datasheet" ""
			(at 295.91 139.7 0)
			(effects
				(font
					(size 1.27 1.27)
					(thickness 0.15)
				)
				(justify left bottom)
				(hide yes)
			)
		)
		(property "Description" ""
			(at 280.67 129.54 0)
			(effects
				(font
					(size 1.27 1.27)
				)
				(hide yes)
			)
		)
		(property "Author" "Antmicro"
			(at 295.91 134.62 0)
			(effects
				(font
					(size 1.27 1.27)
					(thickness 0.15)
				)
				(justify left bottom)
				(hide yes)
			)
		)
		(property "License" "Apache-2.0"
			(at 295.91 137.16 0)
			(effects
				(font
					(size 1.27 1.27)
					(thickness 0.15)
				)
				(justify left bottom)
				(hide yes)
			)
		)
		(pin "1"
		)
		(instances
			(project "data-center-rdimm-ddr5-tester"
				(path ""
					(reference "#PWR0192")
					(unit 1)
				)
			)
		)
	)
	(symbol
		(lib_id "antmicropower:GND")
		(at 143.51 63.5 0)
		(mirror y)
		(unit 1)
		(exclude_from_sim no)
		(in_bom yes)
		(on_board yes)
		(dnp no)
		(property "Reference" "#PWR0230"
			(at 143.51 69.85 0)
			(effects
				(font
					(size 1.27 1.27)
				)
				(hide yes)
			)
		)
		(property "Value" "GND"
			(at 145.415 67.945 0)
			(effects
				(font
					(size 1.27 1.27)
					(thickness 0.15)
				)
				(justify left bottom)
			)
		)
		(property "Footprint" ""
			(at 134.62 71.12 0)
			(effects
				(font
					(size 1.27 1.27)
					(thickness 0.15)
				)
				(justify left bottom)
				(hide yes)
			)
		)
		(property "Datasheet" ""
			(at 134.62 76.2 0)
			(effects
				(font
					(size 1.27 1.27)
					(thickness 0.15)
				)
				(justify left bottom)
				(hide yes)
			)
		)
		(property "Description" ""
			(at 143.51 63.5 0)
			(effects
				(font
					(size 1.27 1.27)
				)
				(hide yes)
			)
		)
		(property "Author" "Antmicro"
			(at 134.62 68.58 0)
			(effects
				(font
					(size 1.27 1.27)
					(thickness 0.15)
				)
				(justify left bottom)
				(hide yes)
			)
		)
		(property "License" "Apache-2.0"
			(at 134.62 71.12 0)
			(effects
				(font
					(size 1.27 1.27)
					(thickness 0.15)
				)
				(justify left bottom)
				(hide yes)
			)
		)
		(pin "1"
		)
		(instances
			(project "data-center-rdimm-ddr5-tester"
				(path ""
					(reference "#PWR0230")
					(unit 1)
				)
			)
		)
	)
	(symbol
		(lib_id "antmicropower:GND")
		(at 383.54 167.64 0)
		(unit 1)
		(exclude_from_sim no)
		(in_bom yes)
		(on_board yes)
		(dnp no)
		(property "Reference" "#PWR0195"
			(at 383.54 173.99 0)
			(effects
				(font
					(size 1.27 1.27)
				)
				(hide yes)
			)
		)
		(property "Value" "GND"
			(at 381.635 172.085 0)
			(effects
				(font
					(size 1.27 1.27)
					(thickness 0.15)
				)
				(justify left bottom)
			)
		)
		(property "Footprint" ""
			(at 392.43 175.26 0)
			(effects
				(font
					(size 1.27 1.27)
					(thickness 0.15)
				)
				(justify left bottom)
				(hide yes)
			)
		)
		(property "Datasheet" ""
			(at 392.43 180.34 0)
			(effects
				(font
					(size 1.27 1.27)
					(thickness 0.15)
				)
				(justify left bottom)
				(hide yes)
			)
		)
		(property "Description" ""
			(at 383.54 167.64 0)
			(effects
				(font
					(size 1.27 1.27)
				)
				(hide yes)
			)
		)
		(property "Author" "Antmicro"
			(at 392.43 172.72 0)
			(effects
				(font
					(size 1.27 1.27)
					(thickness 0.15)
				)
				(justify left bottom)
				(hide yes)
			)
		)
		(property "License" "Apache-2.0"
			(at 392.43 175.26 0)
			(effects
				(font
					(size 1.27 1.27)
					(thickness 0.15)
				)
				(justify left bottom)
				(hide yes)
			)
		)
		(pin "1"
		)
		(instances
			(project "data-center-rdimm-ddr5-tester"
				(path ""
					(reference "#PWR0195")
					(unit 1)
				)
			)
		)
	)
	(symbol
		(lib_id "antmicroCapacitors0402:C_100n_0402")
		(at 372.11 224.79 90)
		(unit 1)
		(exclude_from_sim no)
		(in_bom yes)
		(on_board yes)
		(dnp no)
		(fields_autoplaced yes)
		(property "Reference" "C237"
			(at 374.4341 221.413 90)
			(effects
				(font
					(size 1.27 1.27)
					(thickness 0.15)
				)
				(justify right)
			)
		)
		(property "Value" "C_100n_0402"
			(at 382.27 204.47 0)
			(effects
				(font
					(size 1.27 1.27)
					(thickness 0.15)
				)
				(justify left bottom)
				(hide yes)
			)
		)
		(property "Footprint" "antmicro-footprints:C_0402_1005Metric"
			(at 384.81 204.47 0)
			(effects
				(font
					(size 1.27 1.27)
					(thickness 0.15)
				)
				(justify left bottom)
				(hide yes)
			)
		)
		(property "Datasheet" "https://www.murata.com/products/productdetail?partno=GRM155R61H104KE14%23"
			(at 387.35 204.47 0)
			(effects
				(font
					(size 1.27 1.27)
					(thickness 0.15)
				)
				(justify left bottom)
				(hide yes)
			)
		)
		(property "Description" ""
			(at 372.11 224.79 0)
			(effects
				(font
					(size 1.27 1.27)
				)
				(hide yes)
			)
		)
		(property "MPN" "GRM155R61H104KE14D"
			(at 389.89 204.47 0)
			(effects
				(font
					(size 1.27 1.27)
					(thickness 0.15)
				)
				(justify left bottom)
				(hide yes)
			)
		)
		(property "Manufacturer" "Murata"
			(at 392.43 204.47 0)
			(effects
				(font
					(size 1.27 1.27)
					(thickness 0.15)
				)
				(justify left bottom)
				(hide yes)
			)
		)
		(property "License" "Apache-2.0"
			(at 394.97 204.47 0)
			(effects
				(font
					(size 1.27 1.27)
					(thickness 0.15)
				)
				(justify left bottom)
				(hide yes)
			)
		)
		(property "Author" "Antmicro"
			(at 397.51 204.47 0)
			(effects
				(font
					(size 1.27 1.27)
					(thickness 0.15)
				)
				(justify left bottom)
				(hide yes)
			)
		)
		(property "Val" "100n"
			(at 374.4341 223.9367 90)
			(effects
				(font
					(size 1.27 1.27)
					(thickness 0.15)
				)
				(justify right)
			)
		)
		(property "Voltage" "50V"
			(at 400.05 204.47 0)
			(effects
				(font
					(size 1.27 1.27)
				)
				(justify left bottom)
				(hide yes)
			)
		)
		(property "Dielectric" "X5R"
			(at 402.59 204.47 0)
			(effects
				(font
					(size 1.27 1.27)
				)
				(justify left bottom)
				(hide yes)
			)
		)
		(pin "1"
		)
		(pin "2"
		)
		(instances
			(project "data-center-rdimm-ddr5-tester"
				(path ""
					(reference "C237")
					(unit 1)
				)
			)
		)
	)
	(symbol
		(lib_id "antmicroResistors0402:R_330R_0402")
		(at 269.24 68.58 270)
		(unit 1)
		(exclude_from_sim no)
		(in_bom yes)
		(on_board yes)
		(dnp no)
		(fields_autoplaced yes)
		(property "Reference" "R183"
			(at 270.891 70.2894 90)
			(effects
				(font
					(size 1.27 1.27)
				)
				(justify left)
			)
		)
		(property "Value" "R_330R_0402"
			(at 256.54 88.9 0)
			(effects
				(font
					(size 1.27 1.27)
					(thickness 0.15)
				)
				(justify left bottom)
				(hide yes)
			)
		)
		(property "Footprint" "antmicro-footprints:R_0402_1005Metric"
			(at 254 88.9 0)
			(effects
				(font
					(size 1.27 1.27)
					(thickness 0.15)
				)
				(justify left bottom)
				(hide yes)
			)
		)
		(property "Datasheet" "https://www.bourns.com/docs/product-datasheets/cr.pdf"
			(at 251.46 88.9 0)
			(effects
				(font
					(size 1.27 1.27)
					(thickness 0.15)
				)
				(justify left bottom)
				(hide yes)
			)
		)
		(property "Description" ""
			(at 269.24 68.58 0)
			(effects
				(font
					(size 1.27 1.27)
				)
				(hide yes)
			)
		)
		(property "Manufacturer" "Bourns"
			(at 246.38 88.9 0)
			(effects
				(font
					(size 1.27 1.27)
					(thickness 0.15)
				)
				(justify left bottom)
				(hide yes)
			)
		)
		(property "MPN" "CR0402-FX-3300GLF"
			(at 248.92 88.9 0)
			(effects
				(font
					(size 1.27 1.27)
					(thickness 0.15)
				)
				(justify left bottom)
				(hide yes)
			)
		)
		(property "Val" "330R"
			(at 270.891 72.8197 90)
			(effects
				(font
					(size 1.27 1.27)
					(thickness 0.15)
				)
				(justify left)
			)
		)
		(property "License" "Apache-2.0"
			(at 243.84 88.9 0)
			(effects
				(font
					(size 1.27 1.27)
					(thickness 0.15)
				)
				(justify left bottom)
				(hide yes)
			)
		)
		(property "Author" "Antmicro"
			(at 241.3 88.9 0)
			(effects
				(font
					(size 1.27 1.27)
					(thickness 0.15)
				)
				(justify left bottom)
				(hide yes)
			)
		)
		(property "Tolerance" "1%"
			(at 259.08 88.9 0)
			(effects
				(font
					(size 1.27 1.27)
				)
				(justify left bottom)
				(hide yes)
			)
		)
		(pin "1"
		)
		(pin "2"
		)
		(instances
			(project "data-center-rdimm-ddr5-tester"
				(path ""
					(reference "R183")
					(unit 1)
				)
			)
		)
	)
	(symbol
		(lib_id "antmicroResistors0402:R_330R_0402")
		(at 134.62 261.62 0)
		(unit 1)
		(exclude_from_sim no)
		(in_bom yes)
		(on_board yes)
		(dnp no)
		(property "Reference" "R65"
			(at 139.7 261.62 0)
			(effects
				(font
					(size 1.27 1.27)
				)
				(justify left bottom)
			)
		)
		(property "Value" "R_330R_0402"
			(at 154.94 274.32 0)
			(effects
				(font
					(size 1.27 1.27)
					(thickness 0.15)
				)
				(justify left bottom)
				(hide yes)
			)
		)
		(property "Footprint" "antmicro-footprints:R_0402_1005Metric"
			(at 154.94 276.86 0)
			(effects
				(font
					(size 1.27 1.27)
					(thickness 0.15)
				)
				(justify left bottom)
				(hide yes)
			)
		)
		(property "Datasheet" "https://www.bourns.com/docs/product-datasheets/cr.pdf"
			(at 154.94 279.4 0)
			(effects
				(font
					(size 1.27 1.27)
					(thickness 0.15)
				)
				(justify left bottom)
				(hide yes)
			)
		)
		(property "Description" ""
			(at 134.62 261.62 0)
			(effects
				(font
					(size 1.27 1.27)
				)
				(hide yes)
			)
		)
		(property "Manufacturer" "Bourns"
			(at 154.94 284.48 0)
			(effects
				(font
					(size 1.27 1.27)
					(thickness 0.15)
				)
				(justify left bottom)
				(hide yes)
			)
		)
		(property "MPN" "CR0402-FX-3300GLF"
			(at 154.94 281.94 0)
			(effects
				(font
					(size 1.27 1.27)
					(thickness 0.15)
				)
				(justify left bottom)
				(hide yes)
			)
		)
		(property "Val" "330R"
			(at 129.54 261.62 0)
			(effects
				(font
					(size 1.27 1.27)
					(thickness 0.15)
				)
				(justify left bottom)
			)
		)
		(property "License" "Apache-2.0"
			(at 154.94 287.02 0)
			(effects
				(font
					(size 1.27 1.27)
					(thickness 0.15)
				)
				(justify left bottom)
				(hide yes)
			)
		)
		(property "Author" "Antmicro"
			(at 154.94 289.56 0)
			(effects
				(font
					(size 1.27 1.27)
					(thickness 0.15)
				)
				(justify left bottom)
				(hide yes)
			)
		)
		(property "Tolerance" "1%"
			(at 154.94 271.78 0)
			(effects
				(font
					(size 1.27 1.27)
				)
				(justify left bottom)
				(hide yes)
			)
		)
		(pin "1"
		)
		(pin "2"
		)
		(instances
			(project "data-center-rdimm-ddr5-tester"
				(path ""
					(reference "R65")
					(unit 1)
				)
			)
		)
	)
	(symbol
		(lib_id "antmicroLEDIndicationDiscrete:LED_G_0603_KP-1608CGCK")
		(at 116.84 271.78 0)
		(unit 1)
		(exclude_from_sim no)
		(in_bom yes)
		(on_board yes)
		(dnp no)
		(property "Reference" "D13"
			(at 123.825 270.51 0)
			(effects
				(font
					(size 1.27 1.27)
					(thickness 0.15)
				)
			)
		)
		(property "Value" "LED_G_0603_KP-1608CGCK"
			(at 139.7 279.4 0)
			(effects
				(font
					(size 1.27 1.27)
					(thickness 0.15)
				)
				(justify left bottom)
				(hide yes)
			)
		)
		(property "Footprint" "antmicro-footprints:LED_0603_1608Metric_G"
			(at 139.7 281.94 0)
			(effects
				(font
					(size 1.27 1.27)
					(thickness 0.15)
				)
				(justify left bottom)
				(hide yes)
			)
		)
		(property "Datasheet" "http://www.kingbright.com/attachments/file/psearch//000/00/00/KP-1608CGCK(Ver.23B).pdf"
			(at 139.7 284.48 0)
			(effects
				(font
					(size 1.27 1.27)
					(thickness 0.15)
				)
				(justify left bottom)
				(hide yes)
			)
		)
		(property "Description" ""
			(at 116.84 271.78 0)
			(effects
				(font
					(size 1.27 1.27)
				)
				(hide yes)
			)
		)
		(property "MPN" "KP-1608CGCK"
			(at 119.38 267.97 0)
			(effects
				(font
					(size 1.27 1.27)
					(thickness 0.15)
				)
			)
		)
		(property "Manufacturer" "Kingbright"
			(at 139.7 289.56 0)
			(effects
				(font
					(size 1.27 1.27)
					(thickness 0.15)
				)
				(justify left bottom)
				(hide yes)
			)
		)
		(property "Color" "Green"
			(at 114.935 270.51 0)
			(effects
				(font
					(size 1.27 1.27)
				)
			)
		)
		(property "Author" "Antmicro"
			(at 139.7 292.1 0)
			(effects
				(font
					(size 1.27 1.27)
					(thickness 0.15)
				)
				(justify left bottom)
				(hide yes)
			)
		)
		(property "License" "Apache-2.0"
			(at 139.7 294.64 0)
			(effects
				(font
					(size 1.27 1.27)
					(thickness 0.15)
				)
				(justify left bottom)
				(hide yes)
			)
		)
		(pin "1"
		)
		(pin "2"
		)
		(instances
			(project "data-center-rdimm-ddr5-tester"
				(path ""
					(reference "D13")
					(unit 1)
				)
			)
		)
	)
	(symbol
		(lib_id "antmicroUSBConnectors:USB-C_GCT_USB4105-GF-A")
		(at 62.23 39.37 0)
		(unit 1)
		(exclude_from_sim no)
		(in_bom yes)
		(on_board yes)
		(dnp no)
		(fields_autoplaced yes)
		(property "Reference" "J3"
			(at 48.895 31.75 0)
			(effects
				(font
					(size 1.27 1.27)
					(thickness 0.15)
				)
			)
		)
		(property "Value" "USB-C_GCT_USB4105-GF-A"
			(at 48.895 34.925 0)
			(effects
				(font
					(size 1.27 1.27)
					(thickness 0.15)
				)
				(hide yes)
			)
		)
		(property "Footprint" "antmicro-footprints:USB-C_Receptacle_GCT_USB4105-GF-A"
			(at 100.33 46.99 0)
			(effects
				(font
					(size 1.27 1.27)
					(thickness 0.15)
				)
				(justify left bottom)
				(hide yes)
			)
		)
		(property "Datasheet" "https://gct.co/files/drawings/usb4105.pdf"
			(at 100.33 49.53 0)
			(effects
				(font
					(size 1.27 1.27)
					(thickness 0.15)
				)
				(justify left bottom)
				(hide yes)
			)
		)
		(property "Description" ""
			(at 62.23 39.37 0)
			(effects
				(font
					(size 1.27 1.27)
				)
				(hide yes)
			)
		)
		(property "Manufacturer" "GCT"
			(at 100.33 52.07 0)
			(effects
				(font
					(size 1.27 1.27)
					(thickness 0.15)
				)
				(justify left bottom)
				(hide yes)
			)
		)
		(property "MPN" "USB4105-GF-A"
			(at 48.895 34.29 0)
			(effects
				(font
					(size 1.27 1.27)
					(thickness 0.15)
				)
			)
		)
		(property "Author" "Antmicro"
			(at 100.33 57.15 0)
			(effects
				(font
					(size 1.27 1.27)
					(thickness 0.15)
				)
				(justify left bottom)
				(hide yes)
			)
		)
		(property "License" "Apache-2.0"
			(at 100.33 59.69 0)
			(effects
				(font
					(size 1.27 1.27)
					(thickness 0.15)
				)
				(justify left bottom)
				(hide yes)
			)
		)
		(pin "A6"
		)
		(pin "B1"
		)
		(pin "SH"
		)
		(pin "A1"
		)
		(pin "B8"
		)
		(pin "B5"
		)
		(pin "A12"
		)
		(pin "B7"
		)
		(pin "A5"
		)
		(pin "B12"
		)
		(pin "B4"
		)
		(pin "B9"
		)
		(pin "B6"
		)
		(pin "A9"
		)
		(pin "A7"
		)
		(pin "A4"
		)
		(pin "A8"
		)
		(instances
			(project "data-center-rdimm-ddr5-tester"
				(path ""
					(reference "J3")
					(unit 1)
				)
			)
		)
	)
	(symbol
		(lib_id "antmicroFerriteBeadsandChips:FB_600Z_0.5A_Murata-BLM18AG_0603")
		(at 44.45 167.64 0)
		(unit 1)
		(exclude_from_sim no)
		(in_bom yes)
		(on_board yes)
		(dnp no)
		(fields_autoplaced yes)
		(property "Reference" "FB1"
			(at 46.9519 162.245 0)
			(effects
				(font
					(size 1.27 1.27)
					(thickness 0.15)
				)
			)
		)
		(property "Value" "FB_600Z_0.5A_Murata-BLM18AG_0603"
			(at 59.69 170.18 0)
			(effects
				(font
					(size 1.27 1.27)
					(thickness 0.15)
				)
				(justify left bottom)
				(hide yes)
			)
		)
		(property "Footprint" "antmicro-footprints:FB_0603_1608Metric"
			(at 59.69 175.26 0)
			(effects
				(font
					(size 1.27 1.27)
					(thickness 0.15)
				)
				(justify left bottom)
				(hide yes)
			)
		)
		(property "Datasheet" "https://www.murata.com/en-us/products/productdata/8796738650142/ENFA0003.pdf"
			(at 59.69 177.8 0)
			(effects
				(font
					(size 1.27 1.27)
					(thickness 0.15)
				)
				(justify left bottom)
				(hide yes)
			)
		)
		(property "Description" ""
			(at 44.45 167.64 0)
			(effects
				(font
					(size 1.27 1.27)
				)
				(hide yes)
			)
		)
		(property "Val" "600Z/0.5A"
			(at 46.9519 164.7753 0)
			(effects
				(font
					(size 1.27 1.27)
				)
			)
		)
		(property "MPN" "BLM18AG601SN1D"
			(at 59.69 180.34 0)
			(effects
				(font
					(size 1.27 1.27)
					(thickness 0.15)
				)
				(justify left bottom)
				(hide yes)
			)
		)
		(property "Manufacturer" "Murata"
			(at 59.69 182.88 0)
			(effects
				(font
					(size 1.27 1.27)
					(thickness 0.15)
				)
				(justify left bottom)
				(hide yes)
			)
		)
		(property "Author" "Antmicro"
			(at 59.69 185.42 0)
			(effects
				(font
					(size 1.27 1.27)
					(thickness 0.15)
				)
				(justify left bottom)
				(hide yes)
			)
		)
		(property "License" "Apache-2.0"
			(at 59.69 187.96 0)
			(effects
				(font
					(size 1.27 1.27)
					(thickness 0.15)
				)
				(justify left bottom)
				(hide yes)
			)
		)
		(pin "1"
		)
		(pin "2"
		)
		(instances
			(project "data-center-rdimm-ddr5-tester"
				(path ""
					(reference "FB1")
					(unit 1)
				)
			)
		)
	)
	(symbol
		(lib_id "antmicroResistors0402:R_330R_0402")
		(at 134.62 264.16 0)
		(unit 1)
		(exclude_from_sim no)
		(in_bom yes)
		(on_board yes)
		(dnp no)
		(property "Reference" "R66"
			(at 139.7 264.16 0)
			(effects
				(font
					(size 1.27 1.27)
				)
				(justify left bottom)
			)
		)
		(property "Value" "R_330R_0402"
			(at 154.94 276.86 0)
			(effects
				(font
					(size 1.27 1.27)
					(thickness 0.15)
				)
				(justify left bottom)
				(hide yes)
			)
		)
		(property "Footprint" "antmicro-footprints:R_0402_1005Metric"
			(at 154.94 279.4 0)
			(effects
				(font
					(size 1.27 1.27)
					(thickness 0.15)
				)
				(justify left bottom)
				(hide yes)
			)
		)
		(property "Datasheet" "https://www.bourns.com/docs/product-datasheets/cr.pdf"
			(at 154.94 281.94 0)
			(effects
				(font
					(size 1.27 1.27)
					(thickness 0.15)
				)
				(justify left bottom)
				(hide yes)
			)
		)
		(property "Description" ""
			(at 134.62 264.16 0)
			(effects
				(font
					(size 1.27 1.27)
				)
				(hide yes)
			)
		)
		(property "Manufacturer" "Bourns"
			(at 154.94 287.02 0)
			(effects
				(font
					(size 1.27 1.27)
					(thickness 0.15)
				)
				(justify left bottom)
				(hide yes)
			)
		)
		(property "MPN" "CR0402-FX-3300GLF"
			(at 154.94 284.48 0)
			(effects
				(font
					(size 1.27 1.27)
					(thickness 0.15)
				)
				(justify left bottom)
				(hide yes)
			)
		)
		(property "Val" "330R"
			(at 129.54 264.16 0)
			(effects
				(font
					(size 1.27 1.27)
					(thickness 0.15)
				)
				(justify left bottom)
			)
		)
		(property "License" "Apache-2.0"
			(at 154.94 289.56 0)
			(effects
				(font
					(size 1.27 1.27)
					(thickness 0.15)
				)
				(justify left bottom)
				(hide yes)
			)
		)
		(property "Author" "Antmicro"
			(at 154.94 292.1 0)
			(effects
				(font
					(size 1.27 1.27)
					(thickness 0.15)
				)
				(justify left bottom)
				(hide yes)
			)
		)
		(property "Tolerance" "1%"
			(at 154.94 274.32 0)
			(effects
				(font
					(size 1.27 1.27)
				)
				(justify left bottom)
				(hide yes)
			)
		)
		(pin "1"
		)
		(pin "2"
		)
		(instances
			(project "data-center-rdimm-ddr5-tester"
				(path ""
					(reference "R66")
					(unit 1)
				)
			)
		)
	)
	(symbol
		(lib_id "antmicroResistors0402:R_0R_0402")
		(at 289.56 53.34 90)
		(unit 1)
		(exclude_from_sim no)
		(in_bom no)
		(on_board yes)
		(dnp yes)
		(fields_autoplaced yes)
		(property "Reference" "R251"
			(at 292.1 49.53 90)
			(effects
				(font
					(size 1.27 1.27)
					(thickness 0.15)
				)
				(justify right)
			)
		)
		(property "Value" "R_0R_0402"
			(at 302.26 33.02 0)
			(effects
				(font
					(size 1.27 1.27)
					(thickness 0.15)
				)
				(justify left bottom)
				(hide yes)
			)
		)
		(property "Footprint" "antmicro-footprints:R_0402_1005Metric"
			(at 304.8 33.02 0)
			(effects
				(font
					(size 1.27 1.27)
					(thickness 0.15)
				)
				(justify left bottom)
				(hide yes)
			)
		)
		(property "Datasheet" "https://industrial.panasonic.com/cdbs/www-data/pdf/RDA0000/AOA0000C301.pdf"
			(at 307.34 33.02 0)
			(effects
				(font
					(size 1.27 1.27)
					(thickness 0.15)
				)
				(justify left bottom)
				(hide yes)
			)
		)
		(property "Description" "SMD Chip Resistor, Jumper, 0 ohm, 100 mW, 0402 [1005 Metric], Thick Film, General Purpose"
			(at 289.56 53.34 0)
			(effects
				(font
					(size 1.27 1.27)
				)
				(hide yes)
			)
		)
		(property "MPN" "ERJ2GE0R00X"
			(at 309.88 33.02 0)
			(effects
				(font
					(size 1.27 1.27)
					(thickness 0.15)
				)
				(justify left bottom)
				(hide yes)
			)
		)
		(property "Manufacturer" "Panasonic"
			(at 312.42 33.02 0)
			(effects
				(font
					(size 1.27 1.27)
					(thickness 0.15)
				)
				(justify left bottom)
				(hide yes)
			)
		)
		(property "License" "Apache-2.0"
			(at 314.96 33.02 0)
			(effects
				(font
					(size 1.27 1.27)
					(thickness 0.15)
				)
				(justify left bottom)
				(hide yes)
			)
		)
		(property "Author" "Antmicro"
			(at 317.5 33.02 0)
			(effects
				(font
					(size 1.27 1.27)
					(thickness 0.15)
				)
				(justify left bottom)
				(hide yes)
			)
		)
		(property "Val" "0R"
			(at 292.1 52.07 90)
			(effects
				(font
					(size 1.27 1.27)
					(thickness 0.15)
				)
				(justify right)
			)
		)
		(property "Tolerance" "~"
			(at 299.72 33.02 0)
			(effects
				(font
					(size 1.27 1.27)
				)
				(justify left bottom)
				(hide yes)
			)
		)
		(property "Current" "1A"
			(at 320.04 33.02 0)
			(effects
				(font
					(size 1.27 1.27)
					(thickness 0.15)
				)
				(justify left bottom)
				(hide yes)
			)
		)
		(pin "2"
		)
		(pin "1"
		)
		(instances
			(project "data-center-rdimm-ddr5-tester"
				(path ""
					(reference "R251")
					(unit 1)
				)
			)
		)
	)
	(symbol
		(lib_id "antmicropower:GND")
		(at 379.73 49.53 0)
		(unit 1)
		(exclude_from_sim no)
		(in_bom yes)
		(on_board yes)
		(dnp no)
		(fields_autoplaced yes)
		(property "Reference" "#PWR0517"
			(at 379.73 55.88 0)
			(effects
				(font
					(size 1.27 1.27)
				)
				(hide yes)
			)
		)
		(property "Value" "GND"
			(at 377.825 53.975 0)
			(effects
				(font
					(size 1.27 1.27)
					(thickness 0.15)
				)
				(justify left bottom)
			)
		)
		(property "Footprint" ""
			(at 388.62 57.15 0)
			(effects
				(font
					(size 1.27 1.27)
					(thickness 0.15)
				)
				(justify left bottom)
				(hide yes)
			)
		)
		(property "Datasheet" ""
			(at 388.62 62.23 0)
			(effects
				(font
					(size 1.27 1.27)
					(thickness 0.15)
				)
				(justify left bottom)
				(hide yes)
			)
		)
		(property "Description" ""
			(at 379.73 49.53 0)
			(effects
				(font
					(size 1.27 1.27)
				)
				(hide yes)
			)
		)
		(property "Author" "Antmicro"
			(at 388.62 54.61 0)
			(effects
				(font
					(size 1.27 1.27)
					(thickness 0.15)
				)
				(justify left bottom)
				(hide yes)
			)
		)
		(property "License" "Apache-2.0"
			(at 388.62 57.15 0)
			(effects
				(font
					(size 1.27 1.27)
					(thickness 0.15)
				)
				(justify left bottom)
				(hide yes)
			)
		)
		(pin "1"
		)
		(instances
			(project "data-center-rdimm-ddr5-tester"
				(path ""
					(reference "#PWR0517")
					(unit 1)
				)
			)
		)
	)
	(symbol
		(lib_id "antmicropower:GND")
		(at 370.84 49.53 0)
		(mirror y)
		(unit 1)
		(exclude_from_sim no)
		(in_bom yes)
		(on_board yes)
		(dnp no)
		(fields_autoplaced yes)
		(property "Reference" "#PWR0516"
			(at 370.84 55.88 0)
			(effects
				(font
					(size 1.27 1.27)
				)
				(hide yes)
			)
		)
		(property "Value" "GND"
			(at 372.745 53.975 0)
			(effects
				(font
					(size 1.27 1.27)
					(thickness 0.15)
				)
				(justify left bottom)
			)
		)
		(property "Footprint" ""
			(at 361.95 57.15 0)
			(effects
				(font
					(size 1.27 1.27)
					(thickness 0.15)
				)
				(justify left bottom)
				(hide yes)
			)
		)
		(property "Datasheet" ""
			(at 361.95 62.23 0)
			(effects
				(font
					(size 1.27 1.27)
					(thickness 0.15)
				)
				(justify left bottom)
				(hide yes)
			)
		)
		(property "Description" ""
			(at 370.84 49.53 0)
			(effects
				(font
					(size 1.27 1.27)
				)
				(hide yes)
			)
		)
		(property "Author" "Antmicro"
			(at 361.95 54.61 0)
			(effects
				(font
					(size 1.27 1.27)
					(thickness 0.15)
				)
				(justify left bottom)
				(hide yes)
			)
		)
		(property "License" "Apache-2.0"
			(at 361.95 57.15 0)
			(effects
				(font
					(size 1.27 1.27)
					(thickness 0.15)
				)
				(justify left bottom)
				(hide yes)
			)
		)
		(pin "1"
		)
		(instances
			(project "data-center-rdimm-ddr5-tester"
				(path ""
					(reference "#PWR0516")
					(unit 1)
				)
			)
		)
	)
	(symbol
		(lib_id "antmicroCapacitors0402:C_100n_0402")
		(at 372.11 166.37 90)
		(unit 1)
		(exclude_from_sim no)
		(in_bom yes)
		(on_board yes)
		(dnp no)
		(fields_autoplaced yes)
		(property "Reference" "C130"
			(at 374.4341 162.993 90)
			(effects
				(font
					(size 1.27 1.27)
					(thickness 0.15)
				)
				(justify right)
			)
		)
		(property "Value" "C_100n_0402"
			(at 382.27 146.05 0)
			(effects
				(font
					(size 1.27 1.27)
					(thickness 0.15)
				)
				(justify left bottom)
				(hide yes)
			)
		)
		(property "Footprint" "antmicro-footprints:C_0402_1005Metric"
			(at 384.81 146.05 0)
			(effects
				(font
					(size 1.27 1.27)
					(thickness 0.15)
				)
				(justify left bottom)
				(hide yes)
			)
		)
		(property "Datasheet" "https://www.murata.com/products/productdetail?partno=GRM155R61H104KE14%23"
			(at 387.35 146.05 0)
			(effects
				(font
					(size 1.27 1.27)
					(thickness 0.15)
				)
				(justify left bottom)
				(hide yes)
			)
		)
		(property "Description" ""
			(at 372.11 166.37 0)
			(effects
				(font
					(size 1.27 1.27)
				)
				(hide yes)
			)
		)
		(property "MPN" "GRM155R61H104KE14D"
			(at 389.89 146.05 0)
			(effects
				(font
					(size 1.27 1.27)
					(thickness 0.15)
				)
				(justify left bottom)
				(hide yes)
			)
		)
		(property "Manufacturer" "Murata"
			(at 392.43 146.05 0)
			(effects
				(font
					(size 1.27 1.27)
					(thickness 0.15)
				)
				(justify left bottom)
				(hide yes)
			)
		)
		(property "License" "Apache-2.0"
			(at 394.97 146.05 0)
			(effects
				(font
					(size 1.27 1.27)
					(thickness 0.15)
				)
				(justify left bottom)
				(hide yes)
			)
		)
		(property "Author" "Antmicro"
			(at 397.51 146.05 0)
			(effects
				(font
					(size 1.27 1.27)
					(thickness 0.15)
				)
				(justify left bottom)
				(hide yes)
			)
		)
		(property "Val" "100n"
			(at 374.4341 165.5167 90)
			(effects
				(font
					(size 1.27 1.27)
					(thickness 0.15)
				)
				(justify right)
			)
		)
		(property "Voltage" "50V"
			(at 400.05 146.05 0)
			(effects
				(font
					(size 1.27 1.27)
				)
				(justify left bottom)
				(hide yes)
			)
		)
		(property "Dielectric" "X5R"
			(at 402.59 146.05 0)
			(effects
				(font
					(size 1.27 1.27)
				)
				(justify left bottom)
				(hide yes)
			)
		)
		(pin "1"
		)
		(pin "2"
		)
		(instances
			(project "data-center-rdimm-ddr5-tester"
				(path ""
					(reference "C130")
					(unit 1)
				)
			)
		)
	)
	(symbol
		(lib_id "antmicroTVSDiodes:PESD5V0X1UB")
		(at 91.44 41.91 90)
		(mirror x)
		(unit 1)
		(exclude_from_sim no)
		(in_bom yes)
		(on_board yes)
		(dnp no)
		(fields_autoplaced yes)
		(property "Reference" "D18"
			(at 93.98 43.18 90)
			(effects
				(font
					(size 1.27 1.27)
					(thickness 0.15)
				)
				(justify right)
			)
		)
		(property "Value" "PESD5V0X1UB"
			(at 96.52 57.15 0)
			(effects
				(font
					(size 1.27 1.27)
					(thickness 0.15)
				)
				(justify left bottom)
				(hide yes)
			)
		)
		(property "Footprint" "antmicro-footprints:SOD-523"
			(at 99.06 57.15 0)
			(effects
				(font
					(size 1.27 1.27)
					(thickness 0.15)
				)
				(justify left bottom)
				(hide yes)
			)
		)
		(property "Datasheet" "https://assets.nexperia.com/documents/data-sheet/PESD5V0X1UB.pdf"
			(at 101.6 57.15 0)
			(effects
				(font
					(size 1.27 1.27)
					(thickness 0.15)
				)
				(justify left bottom)
				(hide yes)
			)
		)
		(property "Description" ""
			(at 91.44 41.91 0)
			(effects
				(font
					(size 1.27 1.27)
				)
				(hide yes)
			)
		)
		(property "MPN" "PESD5V0X1UB,135"
			(at 93.98 45.72 90)
			(effects
				(font
					(size 1.27 1.27)
					(thickness 0.15)
				)
				(justify right)
			)
		)
		(property "Manufacturer" "Nexperia"
			(at 104.14 57.15 0)
			(effects
				(font
					(size 1.27 1.27)
					(thickness 0.15)
				)
				(justify left bottom)
				(hide yes)
			)
		)
		(property "Author" "Antmicro"
			(at 106.68 57.15 0)
			(effects
				(font
					(size 1.27 1.27)
					(thickness 0.15)
				)
				(justify left bottom)
				(hide yes)
			)
		)
		(property "License" "Apache-2.0"
			(at 109.22 57.15 0)
			(effects
				(font
					(size 1.27 1.27)
					(thickness 0.15)
				)
				(justify left bottom)
				(hide yes)
			)
		)
		(pin "1"
		)
		(pin "2"
		)
		(instances
			(project "data-center-rdimm-ddr5-tester"
				(path ""
					(reference "D18")
					(unit 1)
				)
			)
		)
	)
	(symbol
		(lib_id "antmicropower:GND")
		(at 50.8 176.53 0)
		(unit 1)
		(exclude_from_sim no)
		(in_bom yes)
		(on_board yes)
		(dnp no)
		(fields_autoplaced yes)
		(property "Reference" "#PWR0227"
			(at 50.8 182.88 0)
			(effects
				(font
					(size 1.27 1.27)
				)
				(hide yes)
			)
		)
		(property "Value" "GND"
			(at 48.895 180.975 0)
			(effects
				(font
					(size 1.27 1.27)
					(thickness 0.15)
				)
				(justify left bottom)
			)
		)
		(property "Footprint" ""
			(at 59.69 184.15 0)
			(effects
				(font
					(size 1.27 1.27)
					(thickness 0.15)
				)
				(justify left bottom)
				(hide yes)
			)
		)
		(property "Datasheet" ""
			(at 59.69 189.23 0)
			(effects
				(font
					(size 1.27 1.27)
					(thickness 0.15)
				)
				(justify left bottom)
				(hide yes)
			)
		)
		(property "Description" ""
			(at 50.8 176.53 0)
			(effects
				(font
					(size 1.27 1.27)
				)
				(hide yes)
			)
		)
		(property "Author" "Antmicro"
			(at 59.69 181.61 0)
			(effects
				(font
					(size 1.27 1.27)
					(thickness 0.15)
				)
				(justify left bottom)
				(hide yes)
			)
		)
		(property "License" "Apache-2.0"
			(at 59.69 184.15 0)
			(effects
				(font
					(size 1.27 1.27)
					(thickness 0.15)
				)
				(justify left bottom)
				(hide yes)
			)
		)
		(pin "1"
		)
		(instances
			(project "data-center-rdimm-ddr5-tester"
				(path ""
					(reference "#PWR0227")
					(unit 1)
				)
			)
		)
	)
	(symbol
		(lib_id "antmicroResistors0402:R_49R9_0402")
		(at 318.77 81.28 90)
		(unit 1)
		(exclude_from_sim no)
		(in_bom yes)
		(on_board yes)
		(dnp no)
		(fields_autoplaced yes)
		(property "Reference" "R233"
			(at 321.31 77.47 90)
			(effects
				(font
					(size 1.27 1.27)
					(thickness 0.15)
				)
				(justify right)
			)
		)
		(property "Value" "R_49R9_0402"
			(at 331.47 60.96 0)
			(effects
				(font
					(size 1.27 1.27)
					(thickness 0.15)
				)
				(justify left bottom)
				(hide yes)
			)
		)
		(property "Footprint" "antmicro-footprints:R_0402_1005Metric"
			(at 334.01 60.96 0)
			(effects
				(font
					(size 1.27 1.27)
					(thickness 0.15)
				)
				(justify left bottom)
				(hide yes)
			)
		)
		(property "Datasheet" "https://www.bourns.com/docs/product-datasheets/cr.pdf"
			(at 336.55 60.96 0)
			(effects
				(font
					(size 1.27 1.27)
					(thickness 0.15)
				)
				(justify left bottom)
				(hide yes)
			)
		)
		(property "Description" ""
			(at 318.77 81.28 0)
			(effects
				(font
					(size 1.27 1.27)
				)
				(hide yes)
			)
		)
		(property "MPN" "CR0402-FX-49R9GLF"
			(at 339.09 60.96 0)
			(effects
				(font
					(size 1.27 1.27)
					(thickness 0.15)
				)
				(justify left bottom)
				(hide yes)
			)
		)
		(property "Manufacturer" "Bourns"
			(at 341.63 60.96 0)
			(effects
				(font
					(size 1.27 1.27)
					(thickness 0.15)
				)
				(justify left bottom)
				(hide yes)
			)
		)
		(property "License" "Apache-2.0"
			(at 344.17 60.96 0)
			(effects
				(font
					(size 1.27 1.27)
					(thickness 0.15)
				)
				(justify left bottom)
				(hide yes)
			)
		)
		(property "Author" "Antmicro"
			(at 346.71 60.96 0)
			(effects
				(font
					(size 1.27 1.27)
					(thickness 0.15)
				)
				(justify left bottom)
				(hide yes)
			)
		)
		(property "Val" "49R9"
			(at 321.31 80.01 90)
			(effects
				(font
					(size 1.27 1.27)
					(thickness 0.15)
				)
				(justify right)
			)
		)
		(property "Tolerance" "1%"
			(at 328.93 60.96 0)
			(effects
				(font
					(size 1.27 1.27)
				)
				(justify left bottom)
				(hide yes)
			)
		)
		(pin "1"
		)
		(pin "2"
		)
		(instances
			(project "data-center-rdimm-ddr5-tester"
				(path ""
					(reference "R233")
					(unit 1)
				)
			)
		)
	)
	(symbol
		(lib_id "antmicropower:GND")
		(at 111.76 275.59 0)
		(unit 1)
		(exclude_from_sim no)
		(in_bom yes)
		(on_board yes)
		(dnp no)
		(property "Reference" "#PWR0223"
			(at 111.76 281.94 0)
			(effects
				(font
					(size 1.27 1.27)
				)
				(hide yes)
			)
		)
		(property "Value" "GND"
			(at 109.855 280.035 0)
			(effects
				(font
					(size 1.27 1.27)
					(thickness 0.15)
				)
				(justify left bottom)
			)
		)
		(property "Footprint" ""
			(at 120.65 283.21 0)
			(effects
				(font
					(size 1.27 1.27)
					(thickness 0.15)
				)
				(justify left bottom)
				(hide yes)
			)
		)
		(property "Datasheet" ""
			(at 120.65 288.29 0)
			(effects
				(font
					(size 1.27 1.27)
					(thickness 0.15)
				)
				(justify left bottom)
				(hide yes)
			)
		)
		(property "Description" ""
			(at 111.76 275.59 0)
			(effects
				(font
					(size 1.27 1.27)
				)
				(hide yes)
			)
		)
		(property "Author" "Antmicro"
			(at 120.65 280.67 0)
			(effects
				(font
					(size 1.27 1.27)
					(thickness 0.15)
				)
				(justify left bottom)
				(hide yes)
			)
		)
		(property "License" "Apache-2.0"
			(at 120.65 283.21 0)
			(effects
				(font
					(size 1.27 1.27)
					(thickness 0.15)
				)
				(justify left bottom)
				(hide yes)
			)
		)
		(pin "1"
		)
		(instances
			(project "data-center-rdimm-ddr5-tester"
				(path ""
					(reference "#PWR0223")
					(unit 1)
				)
			)
		)
	)
	(symbol
		(lib_id "antmicropower:GND")
		(at 59.69 176.53 0)
		(unit 1)
		(exclude_from_sim no)
		(in_bom yes)
		(on_board yes)
		(dnp no)
		(fields_autoplaced yes)
		(property "Reference" "#PWR0247"
			(at 59.69 182.88 0)
			(effects
				(font
					(size 1.27 1.27)
				)
				(hide yes)
			)
		)
		(property "Value" "GND"
			(at 57.785 180.975 0)
			(effects
				(font
					(size 1.27 1.27)
					(thickness 0.15)
				)
				(justify left bottom)
			)
		)
		(property "Footprint" ""
			(at 68.58 184.15 0)
			(effects
				(font
					(size 1.27 1.27)
					(thickness 0.15)
				)
				(justify left bottom)
				(hide yes)
			)
		)
		(property "Datasheet" ""
			(at 68.58 189.23 0)
			(effects
				(font
					(size 1.27 1.27)
					(thickness 0.15)
				)
				(justify left bottom)
				(hide yes)
			)
		)
		(property "Description" ""
			(at 59.69 176.53 0)
			(effects
				(font
					(size 1.27 1.27)
				)
				(hide yes)
			)
		)
		(property "Author" "Antmicro"
			(at 68.58 181.61 0)
			(effects
				(font
					(size 1.27 1.27)
					(thickness 0.15)
				)
				(justify left bottom)
				(hide yes)
			)
		)
		(property "License" "Apache-2.0"
			(at 68.58 184.15 0)
			(effects
				(font
					(size 1.27 1.27)
					(thickness 0.15)
				)
				(justify left bottom)
				(hide yes)
			)
		)
		(pin "1"
		)
		(instances
			(project "data-center-rdimm-ddr5-tester"
				(path ""
					(reference "#PWR0247")
					(unit 1)
				)
			)
		)
	)
	(symbol
		(lib_id "antmicropower:GND")
		(at 276.86 212.09 0)
		(mirror y)
		(unit 1)
		(exclude_from_sim no)
		(in_bom yes)
		(on_board yes)
		(dnp no)
		(property "Reference" "#PWR08"
			(at 276.86 218.44 0)
			(effects
				(font
					(size 1.27 1.27)
				)
				(hide yes)
			)
		)
		(property "Value" "GND"
			(at 278.765 216.535 0)
			(effects
				(font
					(size 1.27 1.27)
					(thickness 0.15)
				)
				(justify left bottom)
			)
		)
		(property "Footprint" ""
			(at 267.97 219.71 0)
			(effects
				(font
					(size 1.27 1.27)
					(thickness 0.15)
				)
				(justify left bottom)
				(hide yes)
			)
		)
		(property "Datasheet" ""
			(at 267.97 224.79 0)
			(effects
				(font
					(size 1.27 1.27)
					(thickness 0.15)
				)
				(justify left bottom)
				(hide yes)
			)
		)
		(property "Description" ""
			(at 276.86 212.09 0)
			(effects
				(font
					(size 1.27 1.27)
				)
				(hide yes)
			)
		)
		(property "Author" "Antmicro"
			(at 267.97 217.17 0)
			(effects
				(font
					(size 1.27 1.27)
					(thickness 0.15)
				)
				(justify left bottom)
				(hide yes)
			)
		)
		(property "License" "Apache-2.0"
			(at 267.97 219.71 0)
			(effects
				(font
					(size 1.27 1.27)
					(thickness 0.15)
				)
				(justify left bottom)
				(hide yes)
			)
		)
		(pin "1"
		)
		(instances
			(project "data-center-rdimm-ddr5-tester"
				(path ""
					(reference "#PWR08")
					(unit 1)
				)
			)
		)
	)
	(symbol
		(lib_id "antmicropower:GND")
		(at 177.8 275.59 0)
		(unit 1)
		(exclude_from_sim no)
		(in_bom yes)
		(on_board yes)
		(dnp no)
		(property "Reference" "#PWR0222"
			(at 177.8 281.94 0)
			(effects
				(font
					(size 1.27 1.27)
				)
				(hide yes)
			)
		)
		(property "Value" "GND"
			(at 175.895 280.035 0)
			(effects
				(font
					(size 1.27 1.27)
					(thickness 0.15)
				)
				(justify left bottom)
			)
		)
		(property "Footprint" ""
			(at 186.69 283.21 0)
			(effects
				(font
					(size 1.27 1.27)
					(thickness 0.15)
				)
				(justify left bottom)
				(hide yes)
			)
		)
		(property "Datasheet" ""
			(at 186.69 288.29 0)
			(effects
				(font
					(size 1.27 1.27)
					(thickness 0.15)
				)
				(justify left bottom)
				(hide yes)
			)
		)
		(property "Description" ""
			(at 177.8 275.59 0)
			(effects
				(font
					(size 1.27 1.27)
				)
				(hide yes)
			)
		)
		(property "Author" "Antmicro"
			(at 186.69 280.67 0)
			(effects
				(font
					(size 1.27 1.27)
					(thickness 0.15)
				)
				(justify left bottom)
				(hide yes)
			)
		)
		(property "License" "Apache-2.0"
			(at 186.69 283.21 0)
			(effects
				(font
					(size 1.27 1.27)
					(thickness 0.15)
				)
				(justify left bottom)
				(hide yes)
			)
		)
		(pin "1"
		)
		(instances
			(project "data-center-rdimm-ddr5-tester"
				(path ""
					(reference "#PWR0222")
					(unit 1)
				)
			)
		)
	)
	(symbol
		(lib_id "antmicroResistors0402:R_22R_0402")
		(at 173.99 147.32 0)
		(unit 1)
		(exclude_from_sim no)
		(in_bom no)
		(on_board yes)
		(dnp yes)
		(property "Reference" "R56"
			(at 180.975 146.05 0)
			(effects
				(font
					(size 1.27 1.27)
				)
			)
		)
		(property "Value" "R_22R_0402"
			(at 194.31 160.02 0)
			(effects
				(font
					(size 1.27 1.27)
					(thickness 0.15)
				)
				(justify left bottom)
				(hide yes)
			)
		)
		(property "Footprint" "antmicro-footprints:R_0402_1005Metric"
			(at 194.31 162.56 0)
			(effects
				(font
					(size 1.27 1.27)
					(thickness 0.15)
				)
				(justify left bottom)
				(hide yes)
			)
		)
		(property "Datasheet" "https://www.bourns.com/docs/product-datasheets/cr.pdf"
			(at 194.31 165.1 0)
			(effects
				(font
					(size 1.27 1.27)
					(thickness 0.15)
				)
				(justify left bottom)
				(hide yes)
			)
		)
		(property "Description" ""
			(at 173.99 147.32 0)
			(effects
				(font
					(size 1.27 1.27)
				)
				(hide yes)
			)
		)
		(property "Manufacturer" "Bourns"
			(at 194.31 170.18 0)
			(effects
				(font
					(size 1.27 1.27)
					(thickness 0.15)
				)
				(justify left bottom)
				(hide yes)
			)
		)
		(property "MPN" "CR0402-FX-22R0GLF"
			(at 194.31 167.64 0)
			(effects
				(font
					(size 1.27 1.27)
					(thickness 0.15)
				)
				(justify left bottom)
				(hide yes)
			)
		)
		(property "Val" "22R"
			(at 172.085 146.05 0)
			(effects
				(font
					(size 1.27 1.27)
					(thickness 0.15)
				)
			)
		)
		(property "License" "Apache-2.0"
			(at 194.31 172.72 0)
			(effects
				(font
					(size 1.27 1.27)
					(thickness 0.15)
				)
				(justify left bottom)
				(hide yes)
			)
		)
		(property "Author" "Antmicro"
			(at 194.31 175.26 0)
			(effects
				(font
					(size 1.27 1.27)
					(thickness 0.15)
				)
				(justify left bottom)
				(hide yes)
			)
		)
		(property "Tolerance" "1%"
			(at 194.31 157.48 0)
			(effects
				(font
					(size 1.27 1.27)
				)
				(justify left bottom)
				(hide yes)
			)
		)
		(pin "1"
		)
		(pin "2"
		)
		(instances
			(project "data-center-rdimm-ddr5-tester"
				(path ""
					(reference "R56")
					(unit 1)
				)
			)
		)
	)
	(symbol
		(lib_id "antmicropower:GND")
		(at 318.77 83.82 0)
		(unit 1)
		(exclude_from_sim no)
		(in_bom yes)
		(on_board yes)
		(dnp no)
		(fields_autoplaced yes)
		(property "Reference" "#PWR0519"
			(at 318.77 90.17 0)
			(effects
				(font
					(size 1.27 1.27)
				)
				(hide yes)
			)
		)
		(property "Value" "GND"
			(at 316.865 88.265 0)
			(effects
				(font
					(size 1.27 1.27)
					(thickness 0.15)
				)
				(justify left bottom)
			)
		)
		(property "Footprint" ""
			(at 327.66 91.44 0)
			(effects
				(font
					(size 1.27 1.27)
					(thickness 0.15)
				)
				(justify left bottom)
				(hide yes)
			)
		)
		(property "Datasheet" ""
			(at 327.66 96.52 0)
			(effects
				(font
					(size 1.27 1.27)
					(thickness 0.15)
				)
				(justify left bottom)
				(hide yes)
			)
		)
		(property "Description" ""
			(at 318.77 83.82 0)
			(effects
				(font
					(size 1.27 1.27)
				)
				(hide yes)
			)
		)
		(property "Author" "Antmicro"
			(at 327.66 88.9 0)
			(effects
				(font
					(size 1.27 1.27)
					(thickness 0.15)
				)
				(justify left bottom)
				(hide yes)
			)
		)
		(property "License" "Apache-2.0"
			(at 327.66 91.44 0)
			(effects
				(font
					(size 1.27 1.27)
					(thickness 0.15)
				)
				(justify left bottom)
				(hide yes)
			)
		)
		(pin "1"
		)
		(instances
			(project "data-center-rdimm-ddr5-tester"
				(path ""
					(reference "#PWR0519")
					(unit 1)
				)
			)
		)
	)
	(symbol
		(lib_id "antmicroResistors0402:R_4k7_0402")
		(at 322.58 161.29 270)
		(unit 1)
		(exclude_from_sim no)
		(in_bom yes)
		(on_board yes)
		(dnp no)
		(property "Reference" "R95"
			(at 323.85 162.56 90)
			(effects
				(font
					(size 1.27 1.27)
				)
				(justify left)
			)
		)
		(property "Value" "R_4k7_0402"
			(at 309.88 181.61 0)
			(effects
				(font
					(size 1.27 1.27)
					(thickness 0.15)
				)
				(justify left bottom)
				(hide yes)
			)
		)
		(property "Footprint" "antmicro-footprints:R_0402_1005Metric"
			(at 307.34 181.61 0)
			(effects
				(font
					(size 1.27 1.27)
					(thickness 0.15)
				)
				(justify left bottom)
				(hide yes)
			)
		)
		(property "Datasheet" "https://www.bourns.com/docs/product-datasheets/cr.pdf"
			(at 304.8 181.61 0)
			(effects
				(font
					(size 1.27 1.27)
					(thickness 0.15)
				)
				(justify left bottom)
				(hide yes)
			)
		)
		(property "Description" ""
			(at 322.58 161.29 0)
			(effects
				(font
					(size 1.27 1.27)
				)
				(hide yes)
			)
		)
		(property "Manufacturer" "Bourns"
			(at 299.72 181.61 0)
			(effects
				(font
					(size 1.27 1.27)
					(thickness 0.15)
				)
				(justify left bottom)
				(hide yes)
			)
		)
		(property "MPN" "CR0402-FX-4701GLF"
			(at 302.26 181.61 0)
			(effects
				(font
					(size 1.27 1.27)
					(thickness 0.15)
				)
				(justify left bottom)
				(hide yes)
			)
		)
		(property "Val" "4k7"
			(at 323.85 165.735 90)
			(effects
				(font
					(size 1.27 1.27)
					(thickness 0.15)
				)
				(justify left)
			)
		)
		(property "License" "Apache-2.0"
			(at 297.18 181.61 0)
			(effects
				(font
					(size 1.27 1.27)
					(thickness 0.15)
				)
				(justify left bottom)
				(hide yes)
			)
		)
		(property "Author" "Antmicro"
			(at 294.64 181.61 0)
			(effects
				(font
					(size 1.27 1.27)
					(thickness 0.15)
				)
				(justify left bottom)
				(hide yes)
			)
		)
		(property "Tolerance" "1%"
			(at 312.42 181.61 0)
			(effects
				(font
					(size 1.27 1.27)
				)
				(justify left bottom)
				(hide yes)
			)
		)
		(pin "1"
		)
		(pin "2"
		)
		(instances
			(project "data-center-rdimm-ddr5-tester"
				(path ""
					(reference "R95")
					(unit 1)
				)
			)
		)
	)
	(symbol
		(lib_id "antmicroCapacitors0402:C_100n_0402")
		(at 383.54 166.37 90)
		(unit 1)
		(exclude_from_sim no)
		(in_bom yes)
		(on_board yes)
		(dnp no)
		(fields_autoplaced yes)
		(property "Reference" "C131"
			(at 385.8641 162.993 90)
			(effects
				(font
					(size 1.27 1.27)
					(thickness 0.15)
				)
				(justify right)
			)
		)
		(property "Value" "C_100n_0402"
			(at 393.7 146.05 0)
			(effects
				(font
					(size 1.27 1.27)
					(thickness 0.15)
				)
				(justify left bottom)
				(hide yes)
			)
		)
		(property "Footprint" "antmicro-footprints:C_0402_1005Metric"
			(at 396.24 146.05 0)
			(effects
				(font
					(size 1.27 1.27)
					(thickness 0.15)
				)
				(justify left bottom)
				(hide yes)
			)
		)
		(property "Datasheet" "https://www.murata.com/products/productdetail?partno=GRM155R61H104KE14%23"
			(at 398.78 146.05 0)
			(effects
				(font
					(size 1.27 1.27)
					(thickness 0.15)
				)
				(justify left bottom)
				(hide yes)
			)
		)
		(property "Description" ""
			(at 383.54 166.37 0)
			(effects
				(font
					(size 1.27 1.27)
				)
				(hide yes)
			)
		)
		(property "MPN" "GRM155R61H104KE14D"
			(at 401.32 146.05 0)
			(effects
				(font
					(size 1.27 1.27)
					(thickness 0.15)
				)
				(justify left bottom)
				(hide yes)
			)
		)
		(property "Manufacturer" "Murata"
			(at 403.86 146.05 0)
			(effects
				(font
					(size 1.27 1.27)
					(thickness 0.15)
				)
				(justify left bottom)
				(hide yes)
			)
		)
		(property "License" "Apache-2.0"
			(at 406.4 146.05 0)
			(effects
				(font
					(size 1.27 1.27)
					(thickness 0.15)
				)
				(justify left bottom)
				(hide yes)
			)
		)
		(property "Author" "Antmicro"
			(at 408.94 146.05 0)
			(effects
				(font
					(size 1.27 1.27)
					(thickness 0.15)
				)
				(justify left bottom)
				(hide yes)
			)
		)
		(property "Val" "100n"
			(at 385.8641 165.5167 90)
			(effects
				(font
					(size 1.27 1.27)
					(thickness 0.15)
				)
				(justify right)
			)
		)
		(property "Voltage" "50V"
			(at 411.48 146.05 0)
			(effects
				(font
					(size 1.27 1.27)
				)
				(justify left bottom)
				(hide yes)
			)
		)
		(property "Dielectric" "X5R"
			(at 414.02 146.05 0)
			(effects
				(font
					(size 1.27 1.27)
				)
				(justify left bottom)
				(hide yes)
			)
		)
		(pin "1"
		)
		(pin "2"
		)
		(instances
			(project "data-center-rdimm-ddr5-tester"
				(path ""
					(reference "C131")
					(unit 1)
				)
			)
		)
	)
)
